FILE_TYPE = MACRO_DRAWING;
SET COLOR_WIRE YELLOW;
SET COLOR_PROP ORANGE;
SET COLOR_DOT WHITE;
SET COLOR_ARC YELLOW;
SET COLOR_BODY GREEN;
SET COLOR_NOTE PURPLE;
SET PROP_DISPLAY VALUE;
SET PAGE_NUMBER P201;
FORCEADD OFFPAGE..1
(-8575 4075);
FORCEPROP 2 LAST $XR0 80 
J 0
(-8796 4075);
DISPLAY 0.638298 (-8796 4075);
PAINT MONO (-8796 4075);
FORCEPROP 2 LAST CDS_LIB standard
J 0
(-8575 4075);
DISPLAY INVISIBLE (-8575 4075);
FORCEPROP 1 LAST OFFPAGE TRUE
J 0
(-8250 3950);
DISPLAY 0.872340 (-8250 3950);
PAINT GREEN (-8250 3950);
DISPLAY INVISIBLE (-8250 3950);
FORCEPROP 1 LAST COMMENT_BODY TRUE
J 0
(-8450 3975);
DISPLAY 0.872340 (-8450 3975);
PAINT GREEN (-8450 3975);
DISPLAY INVISIBLE (-8450 3975);
FORCEPROP 2 LAST PATH I1
J 0
(-8525 4150);
DISPLAY 1.021277 (-8525 4150);
DISPLAY INVISIBLE (-8525 4150);
FORCEADD UNIVERSAL_GND..1
(-6425 2800);
FORCEPROP 3 LASTPIN (-6425 2850) SIG_NAME GND\g
J 0
(-6415 2860);
DISPLAY 0.659574 (-6415 2860);
PAINT MONO (-6415 2860);
DISPLAY INVISIBLE (-6415 2860);
FORCEPROP 2 LAST CDS_LIB pure_quanta_power
J 0
(-6425 2800);
DISPLAY INVISIBLE (-6425 2800);
FORCEPROP 1 LAST PATH I10
J 0
(-6350 2800);
DISPLAY 0.872340 (-6350 2800);
PAINT AQUA (-6350 2800);
DISPLAY INVISIBLE (-6350 2800);
FORCEPROP 1 LAST HDL_POWER GND
J 1
(-6400 2725);
DISPLAY 0.872340 (-6400 2725);
PAINT GREEN (-6400 2725);
DISPLAY INVISIBLE (-6400 2725);
FORCEADD Q_RES..2
(-6425 3050);
FORCEPROP 1 LAST LOCATION PR8
J 0
(-6380 3175);
DISPLAY 0.489362 (-6380 3175);
PAINT SKYBLUE (-6380 3175);
FORCEPROP 2 LAST SEC 1
J 0
(-6363 3293);
DISPLAY 0.680851 (-6363 3293);
PAINT MONO (-6363 3293);
DISPLAY INVISIBLE (-6363 3293);
FORCEPROP 1 LASTPIN (-6425 3150) $PN 1
J 0
(-6420 3112);
DISPLAY 0.489362 (-6420 3112);
FORCEPROP 1 LASTPIN (-6425 2950) $PN 2
J 0
(-6420 2960);
DISPLAY 0.489362 (-6420 2960);
FORCEPROP 1 LAST WATTAGE 1/16W
J 0
(-6385 3025);
DISPLAY 0.489362 (-6385 3025);
PAINT SKYBLUE (-6385 3025);
FORCEPROP 1 LAST MATERIAL CHIP
J 0
(-6385 2975);
DISPLAY 0.489362 (-6385 2975);
PAINT SKYBLUE (-6385 2975);
FORCEPROP 1 LAST TOLERANCE 1%
J 0
(-6380 3075);
DISPLAY 0.489362 (-6380 3075);
PAINT SKYBLUE (-6380 3075);
FORCEPROP 1 LAST VALUE 8.66K
J 0
(-6380 3125);
DISPLAY 0.489362 (-6380 3125);
PAINT SKYBLUE (-6380 3125);
FORCEPROP 1 LAST PART_NUMBER CS28662FB14
J 0
(-6385 2925);
DISPLAY 0.489362 (-6385 2925);
PAINT SKYBLUE (-6385 2925);
FORCEPROP 1 LAST PACK_TYPE 0402LF
J 0
(-6385 2875);
DISPLAY 0.489362 (-6385 2875);
PAINT SKYBLUE (-6385 2875);
FORCEPROP 2 LAST CDS_LIB pure_quanta
R 3
J 0
(-6425 3050);
DISPLAY INVISIBLE (-6425 3050);
FORCEPROP 2 LAST SEC_TYPE 0402LF
J 0
(-6363 3293);
DISPLAY 1.021277 (-6363 3293);
DISPLAY INVISIBLE (-6363 3293);
FORCEPROP 1 LAST PATH I11
J 0
(-6375 3225);
DISPLAY 0.978723 (-6375 3225);
PAINT WHITE (-6375 3225);
DISPLAY INVISIBLE (-6375 3225);
FORCEADD MPQ8633BGLEC838Z..1
(-5475 3900);
FORCEPROP 1 LAST LOCATION PU3
J 0
(-5722 4807);
DISPLAY 0.489362 (-5722 4807);
PAINT SKYBLUE (-5722 4807);
FORCEPROP 0 LAST $SEC 1
J 0
(-5725 4975);
DISPLAY 0.680851 (-5725 4975);
PAINT MONO (-5725 4975);
DISPLAY INVISIBLE (-5725 4975);
FORCEPROP 0 LAST CDS_SEC 1
J 0
(-5725 4975);
DISPLAY 1.021277 (-5725 4975);
DISPLAY INVISIBLE (-5725 4975);
FORCEPROP 0 LASTPIN (-5075 3225) $PN 2
J 0
(-5065 3235);
DISPLAY 0.489362 (-5065 3235);
PAINT MONO (-5065 3235);
FORCEPROP 0 LASTPIN (-5075 4375) $PN 1
J 0
(-5065 4385);
DISPLAY 0.489362 (-5065 4385);
PAINT MONO (-5065 4385);
FORCEPROP 0 LASTPIN (-5875 3275) $PN 3
J 2
(-5885 3285);
DISPLAY 0.489362 (-5885 3285);
PAINT MONO (-5885 3285);
FORCEPROP 0 LASTPIN (-5875 4075) $PN 8
J 2
(-5885 4085);
DISPLAY 0.489362 (-5885 4085);
PAINT MONO (-5885 4085);
FORCEPROP 0 LASTPIN (-5075 3625) $PN 7
J 0
(-5065 3635);
DISPLAY 0.489362 (-5065 3635);
PAINT MONO (-5065 3635);
FORCEPROP 0 LASTPIN (-5875 3875) $PN 4
J 2
(-5885 3885);
DISPLAY 0.489362 (-5885 3885);
PAINT MONO (-5885 3885);
FORCEPROP 0 LASTPIN (-5075 3275) $PN 11_18
J 0
(-5065 3285);
DISPLAY 0.489362 (-5065 3285);
PAINT MONO (-5065 3285);
FORCEPROP 0 LASTPIN (-5075 4575) $PN 9
J 0
(-5065 4585);
DISPLAY 0.489362 (-5065 4585);
PAINT MONO (-5065 4585);
FORCEPROP 0 LASTPIN (-5075 3475) $PN 6
J 0
(-5065 3485);
DISPLAY 0.489362 (-5065 3485);
PAINT MONO (-5065 3485);
FORCEPROP 0 LASTPIN (-5075 4075) $PN 20
J 0
(-5065 4085);
DISPLAY 0.489362 (-5065 4085);
PAINT MONO (-5065 4085);
FORCEPROP 0 LASTPIN (-5075 3375) $PN 5
J 0
(-5065 3385);
DISPLAY 0.489362 (-5065 3385);
PAINT MONO (-5065 3385);
FORCEPROP 0 LASTPIN (-5875 3625) $PN 19
J 2
(-5885 3635);
DISPLAY 0.489362 (-5885 3635);
PAINT MONO (-5885 3635);
FORCEPROP 0 LASTPIN (-5875 4575) $PN 10
J 2
(-5885 4585);
DISPLAY 0.489362 (-5885 4585);
PAINT MONO (-5885 4585);
FORCEPROP 0 LASTPIN (-5875 4525) $PN 21
J 2
(-5885 4535);
DISPLAY 0.489362 (-5885 4535);
PAINT MONO (-5885 4535);
FORCEPROP 2 LAST PART_TYPE SMLF
J 0
(-5725 4925);
DISPLAY 0.680851 (-5725 4925);
FORCEPROP 1 LAST MATERIAL IC
J 0
(-5722 4629);
DISPLAY 0.489362 (-5722 4629);
PAINT SKYBLUE (-5722 4629);
FORCEPROP 2 LAST VALUE MPQ8633BGLE-C838-Z
J 0
(-5725 4875);
DISPLAY 0.489362 (-5725 4875);
PAINT SKYBLUE (-5725 4875);
FORCEPROP 1 LAST PART_NUMBER AL008633005
J 0
(-5722 4708);
DISPLAY 0.489362 (-5722 4708);
PAINT SKYBLUE (-5722 4708);
FORCEPROP 1 LAST CDS_LMAN_SYM_OUTLINE -250,725,250,-725
J 0
(-5475 3900);
DISPLAY 0.468085 (-5475 3900);
PAINT GREEN (-5475 3900);
DISPLAY INVISIBLE (-5475 3900);
FORCEPROP 1 LAST NEEDS_NO_SIZE TRUE
J 0
(-5475 3900);
DISPLAY 0.723404 (-5475 3900);
PAINT GREEN (-5475 3900);
DISPLAY INVISIBLE (-5475 3900);
FORCEPROP 2 LAST CDS_LIB pure_quanta
J 0
(-5475 3900);
DISPLAY INVISIBLE (-5475 3900);
FORCEPROP 1 LAST PATH I12
J 0
(-5475 3900);
DISPLAY 0.723404 (-5475 3900);
PAINT GREEN (-5475 3900);
DISPLAY INVISIBLE (-5475 3900);
FORCEADD UNIVERSAL_GND..1
(-4925 2950);
FORCEPROP 3 LASTPIN (-4925 3000) SIG_NAME GND\g
J 0
(-4915 3010);
DISPLAY 0.659574 (-4915 3010);
PAINT MONO (-4915 3010);
DISPLAY INVISIBLE (-4915 3010);
FORCEPROP 2 LAST CDS_LIB pure_quanta_power
J 0
(-4925 2950);
DISPLAY INVISIBLE (-4925 2950);
FORCEPROP 1 LAST PATH I13
J 0
(-4850 2950);
DISPLAY 0.872340 (-4850 2950);
PAINT AQUA (-4850 2950);
DISPLAY INVISIBLE (-4850 2950);
FORCEPROP 1 LAST HDL_POWER GND
J 1
(-4900 2875);
DISPLAY 0.872340 (-4900 2875);
PAINT GREEN (-4900 2875);
DISPLAY INVISIBLE (-4900 2875);
FORCEADD UNIVERSAL_GND..1
(-4750 2950);
FORCEPROP 3 LASTPIN (-4750 3000) SIG_NAME GND\g
J 0
(-4740 3010);
DISPLAY 0.659574 (-4740 3010);
PAINT MONO (-4740 3010);
DISPLAY INVISIBLE (-4740 3010);
FORCEPROP 2 LAST CDS_LIB pure_quanta_power
J 0
(-4750 2950);
DISPLAY INVISIBLE (-4750 2950);
FORCEPROP 1 LAST PATH I14
J 0
(-4675 2950);
DISPLAY 0.872340 (-4675 2950);
PAINT AQUA (-4675 2950);
DISPLAY INVISIBLE (-4675 2950);
FORCEPROP 1 LAST HDL_POWER GND
J 1
(-4725 2875);
DISPLAY 0.872340 (-4725 2875);
PAINT GREEN (-4725 2875);
DISPLAY INVISIBLE (-4725 2875);
FORCEADD Q_CAP..1
(-4750 3200);
FORCEPROP 1 LAST LOCATION PC153
J 0
(-4700 3250);
DISPLAY 0.489362 (-4700 3250);
PAINT SKYBLUE (-4700 3250);
FORCEPROP 0 LAST $SEC 1
J 0
(-4700 3325);
DISPLAY 0.680851 (-4700 3325);
PAINT MONO (-4700 3325);
DISPLAY INVISIBLE (-4700 3325);
FORCEPROP 2 LAST CDS_SEC 1
J 0
(-4700 3400);
DISPLAY 0.680851 (-4700 3400);
DISPLAY INVISIBLE (-4700 3400);
FORCEPROP 1 LASTPIN (-4750 3300) $PN 1
J 0
(-4740 3280);
DISPLAY 0.489362 (-4740 3280);
PAINT MONO (-4740 3280);
FORCEPROP 1 LASTPIN (-4750 3100) $PN 2
J 0
(-4740 3080);
DISPLAY 0.489362 (-4740 3080);
PAINT MONO (-4740 3080);
FORCEPROP 1 LAST MATERIAL X7R
J 0
(-4700 3050);
DISPLAY 0.489362 (-4700 3050);
PAINT SKYBLUE (-4700 3050);
FORCEPROP 1 LAST TOLERANCE 10%
J 0
(-4700 3100);
DISPLAY 0.489362 (-4700 3100);
PAINT SKYBLUE (-4700 3100);
FORCEPROP 1 LAST VALUE 0.022UF
J 0
(-4700 3200);
DISPLAY 0.489362 (-4700 3200);
PAINT SKYBLUE (-4700 3200);
FORCEPROP 1 LAST PART_NUMBER CH3224K1B01
J 0
(-4700 3000);
DISPLAY 0.489362 (-4700 3000);
PAINT SKYBLUE (-4700 3000);
FORCEPROP 1 LAST VOLTAGE 25V
J 0
(-4700 3150);
DISPLAY 0.489362 (-4700 3150);
PAINT SKYBLUE (-4700 3150);
FORCEPROP 1 LAST PACK_TYPE 0402
J 0
(-4700 2950);
DISPLAY 0.489362 (-4700 2950);
PAINT SKYBLUE (-4700 2950);
FORCEPROP 2 LAST CDS_LIB pure_quanta
J 0
(-4750 3200);
DISPLAY INVISIBLE (-4750 3200);
FORCEPROP 1 LAST PATH I15
J 0
(-4700 3350);
DISPLAY 0.978723 (-4700 3350);
PAINT WHITE (-4700 3350);
DISPLAY INVISIBLE (-4700 3350);
FORCEADD Q_RES..2
(-3925 3325);
FORCEPROP 1 LAST LOCATION PR147
J 0
(-3875 3400);
DISPLAY 0.489362 (-3875 3400);
PAINT SKYBLUE (-3875 3400);
FORCEPROP 2 LAST $SEC 1
J 0
(-3875 3550);
DISPLAY 0.680851 (-3875 3550);
PAINT MONO (-3875 3550);
DISPLAY INVISIBLE (-3875 3550);
FORCEPROP 2 LAST CDS_SEC 1
J 0
(-3875 3550);
DISPLAY 0.680851 (-3875 3550);
DISPLAY INVISIBLE (-3875 3550);
FORCEPROP 1 LASTPIN (-3925 3425) $PN 1
J 0
(-3920 3387);
DISPLAY 0.489362 (-3920 3387);
FORCEPROP 1 LASTPIN (-3925 3225) $PN 2
J 0
(-3920 3235);
DISPLAY 0.489362 (-3920 3235);
FORCEPROP 1 LAST WATTAGE 1/16W
J 0
(-3875 3250);
DISPLAY 0.489362 (-3875 3250);
PAINT SKYBLUE (-3875 3250);
FORCEPROP 1 LAST MATERIAL CHIP
J 0
(-3875 3200);
DISPLAY 0.489362 (-3875 3200);
PAINT SKYBLUE (-3875 3200);
FORCEPROP 1 LAST TOLERANCE 1%
J 0
(-3875 3300);
DISPLAY 0.489362 (-3875 3300);
PAINT SKYBLUE (-3875 3300);
FORCEPROP 1 LAST VALUE 10K
J 0
(-3875 3350);
DISPLAY 0.489362 (-3875 3350);
PAINT SKYBLUE (-3875 3350);
FORCEPROP 1 LAST PART_NUMBER TMP_QCS31002FB26
J 0
(-3875 3150);
DISPLAY 0.489362 (-3875 3150);
PAINT SKYBLUE (-3875 3150);
FORCEPROP 1 LAST PACK_TYPE 0402LF
J 0
(-3875 3100);
DISPLAY 0.489362 (-3875 3100);
PAINT SKYBLUE (-3875 3100);
FORCEPROP 2 LAST CDS_LIB pure_quanta
J 0
(-3925 3325);
DISPLAY INVISIBLE (-3925 3325);
FORCEPROP 1 LAST PATH I18
J 0
(-3875 3500);
DISPLAY 0.978723 (-3875 3500);
PAINT WHITE (-3875 3500);
DISPLAY INVISIBLE (-3875 3500);
FORCEADD Q_CAP..1
(-4200 4225);
FORCEPROP 1 LAST LOCATION PC19
J 0
(-4150 4400);
DISPLAY 0.489362 (-4150 4400);
PAINT SKYBLUE (-4150 4400);
FORCEPROP 2 LAST SEC 1
J 0
(-4126 4444);
DISPLAY 0.680851 (-4126 4444);
PAINT MONO (-4126 4444);
DISPLAY INVISIBLE (-4126 4444);
FORCEPROP 1 LASTPIN (-4200 4325) $PN 1
J 0
(-4190 4305);
DISPLAY 0.489362 (-4190 4305);
FORCEPROP 1 LASTPIN (-4200 4125) $PN 2
J 0
(-4190 4105);
DISPLAY 0.489362 (-4190 4105);
FORCEPROP 1 LAST MATERIAL X7R
J 0
(-4150 4200);
DISPLAY 0.489362 (-4150 4200);
PAINT SKYBLUE (-4150 4200);
FORCEPROP 1 LAST TOLERANCE 10%
J 0
(-4150 4250);
DISPLAY 0.489362 (-4150 4250);
PAINT SKYBLUE (-4150 4250);
FORCEPROP 1 LAST VALUE 0.22UF
J 0
(-4150 4350);
DISPLAY 0.489362 (-4150 4350);
PAINT SKYBLUE (-4150 4350);
FORCEPROP 1 LAST PART_NUMBER CH4223K1B00
J 0
(-4150 4150);
DISPLAY 0.489362 (-4150 4150);
PAINT SKYBLUE (-4150 4150);
FORCEPROP 1 LAST VOLTAGE 16V
J 0
(-4150 4300);
DISPLAY 0.489362 (-4150 4300);
PAINT SKYBLUE (-4150 4300);
FORCEPROP 1 LAST PACK_TYPE 0402
J 0
(-4150 4100);
DISPLAY 0.489362 (-4150 4100);
PAINT SKYBLUE (-4150 4100);
FORCEPROP 2 LAST CDS_LIB pure_quanta
J 0
(-4200 4225);
PAINT MONO (-4200 4225);
DISPLAY INVISIBLE (-4200 4225);
FORCEPROP 2 LAST SEC_TYPE 0402
J 0
(-4126 4444);
DISPLAY 1.021277 (-4126 4444);
DISPLAY INVISIBLE (-4126 4444);
FORCEPROP 1 LAST PATH I19
J 0
(-4150 4375);
DISPLAY 0.978723 (-4150 4375);
PAINT WHITE (-4150 4375);
DISPLAY INVISIBLE (-4150 4375);
FORCEPROP 2 LAST ROOM VR_CORE1_POWER_STAGE_1
J 1
(-4145 4351);
DISPLAY 1.021277 (-4145 4351);
PAINT RED (-4145 4351);
DISPLAY INVISIBLE (-4145 4351);
FORCEADD Q_CAP..1
(-7625 4625);
FORCEPROP 1 LAST LOCATION PC61
J 0
(-7575 4725);
DISPLAY 0.489362 (-7575 4725);
PAINT SKYBLUE (-7575 4725);
FORCEPROP 0 LAST $SEC 1
J 0
(-7575 4750);
DISPLAY 0.680851 (-7575 4750);
PAINT MONO (-7575 4750);
DISPLAY INVISIBLE (-7575 4750);
FORCEPROP 0 LAST CDS_SEC 1
J 0
(-7575 4775);
DISPLAY 1.021277 (-7575 4775);
DISPLAY INVISIBLE (-7575 4775);
FORCEPROP 1 LASTPIN (-7625 4725) $PN 1
J 0
(-7615 4705);
DISPLAY 0.489362 (-7615 4705);
PAINT MONO (-7615 4705);
FORCEPROP 1 LASTPIN (-7625 4525) $PN 2
J 0
(-7615 4505);
DISPLAY 0.489362 (-7615 4505);
PAINT MONO (-7615 4505);
FORCEPROP 1 LAST MATERIAL X6S
J 0
(-7575 4525);
DISPLAY 0.489362 (-7575 4525);
PAINT SKYBLUE (-7575 4525);
FORCEPROP 1 LAST TOLERANCE 10%
J 0
(-7575 4575);
DISPLAY 0.489362 (-7575 4575);
PAINT SKYBLUE (-7575 4575);
FORCEPROP 1 LAST VALUE 10UF
J 0
(-7575 4675);
DISPLAY 0.489362 (-7575 4675);
PAINT SKYBLUE (-7575 4675);
FORCEPROP 1 LAST PART_NUMBER CH6104KEA00
J 0
(-7575 4475);
DISPLAY 0.489362 (-7575 4475);
PAINT SKYBLUE (-7575 4475);
FORCEPROP 1 LAST VOLTAGE 25V
J 0
(-7575 4625);
DISPLAY 0.489362 (-7575 4625);
PAINT SKYBLUE (-7575 4625);
FORCEPROP 1 LAST PACK_TYPE C0805
J 0
(-7575 4425);
DISPLAY 0.489362 (-7575 4425);
PAINT SKYBLUE (-7575 4425);
FORCEPROP 2 LAST CDS_LIB pure_quanta
J 0
(-7625 4625);
DISPLAY INVISIBLE (-7625 4625);
FORCEPROP 1 LAST PATH I20
J 0
(-7575 4775);
DISPLAY 0.978723 (-7575 4775);
PAINT WHITE (-7575 4775);
DISPLAY INVISIBLE (-7575 4775);
FORCEADD Q_CAP..1
(-7225 4625);
FORCEPROP 1 LAST LOCATION PC150
J 0
(-7175 4725);
DISPLAY 0.489362 (-7175 4725);
PAINT SKYBLUE (-7175 4725);
FORCEPROP 0 LAST $SEC 1
J 0
(-7175 4750);
DISPLAY 0.680851 (-7175 4750);
PAINT MONO (-7175 4750);
DISPLAY INVISIBLE (-7175 4750);
FORCEPROP 0 LAST CDS_SEC 1
J 0
(-7175 4775);
DISPLAY 1.021277 (-7175 4775);
DISPLAY INVISIBLE (-7175 4775);
FORCEPROP 1 LASTPIN (-7225 4725) $PN 1
J 0
(-7215 4705);
DISPLAY 0.489362 (-7215 4705);
PAINT MONO (-7215 4705);
FORCEPROP 1 LASTPIN (-7225 4525) $PN 2
J 0
(-7215 4505);
DISPLAY 0.489362 (-7215 4505);
PAINT MONO (-7215 4505);
FORCEPROP 1 LAST MATERIAL X6S
J 0
(-7175 4525);
DISPLAY 0.489362 (-7175 4525);
PAINT SKYBLUE (-7175 4525);
FORCEPROP 1 LAST TOLERANCE 10%
J 0
(-7175 4575);
DISPLAY 0.489362 (-7175 4575);
PAINT SKYBLUE (-7175 4575);
FORCEPROP 1 LAST VALUE 10UF
J 0
(-7175 4675);
DISPLAY 0.489362 (-7175 4675);
PAINT SKYBLUE (-7175 4675);
FORCEPROP 1 LAST PART_NUMBER CH6104KEA00
J 0
(-7175 4475);
DISPLAY 0.489362 (-7175 4475);
PAINT SKYBLUE (-7175 4475);
FORCEPROP 1 LAST VOLTAGE 25V
J 0
(-7175 4625);
DISPLAY 0.489362 (-7175 4625);
PAINT SKYBLUE (-7175 4625);
FORCEPROP 1 LAST PACK_TYPE C0805
J 0
(-7175 4425);
DISPLAY 0.489362 (-7175 4425);
PAINT SKYBLUE (-7175 4425);
FORCEPROP 2 LAST CDS_LIB pure_quanta
J 0
(-7225 4625);
DISPLAY INVISIBLE (-7225 4625);
FORCEPROP 1 LAST PATH I21
J 0
(-7175 4775);
DISPLAY 0.978723 (-7175 4775);
PAINT WHITE (-7175 4775);
DISPLAY INVISIBLE (-7175 4775);
FORCEADD Q_CAP..1
(-6775 4625);
FORCEPROP 1 LAST LOCATION PC152
J 0
(-6725 4725);
DISPLAY 0.489362 (-6725 4725);
PAINT SKYBLUE (-6725 4725);
FORCEPROP 0 LAST $SEC 1
J 0
(-6725 4750);
DISPLAY 0.680851 (-6725 4750);
PAINT MONO (-6725 4750);
DISPLAY INVISIBLE (-6725 4750);
FORCEPROP 0 LAST CDS_SEC 1
J 0
(-6725 4775);
DISPLAY 0.680851 (-6725 4775);
DISPLAY INVISIBLE (-6725 4775);
FORCEPROP 1 LASTPIN (-6775 4725) $PN 1
J 0
(-6765 4705);
DISPLAY 0.489362 (-6765 4705);
PAINT MONO (-6765 4705);
FORCEPROP 1 LASTPIN (-6775 4525) $PN 2
J 0
(-6765 4505);
DISPLAY 0.489362 (-6765 4505);
PAINT MONO (-6765 4505);
FORCEPROP 1 LAST MATERIAL X6S
J 0
(-6725 4525);
DISPLAY 0.489362 (-6725 4525);
PAINT SKYBLUE (-6725 4525);
FORCEPROP 1 LAST TOLERANCE 10%
J 0
(-6725 4575);
DISPLAY 0.489362 (-6725 4575);
PAINT SKYBLUE (-6725 4575);
FORCEPROP 1 LAST VALUE 10UF
J 0
(-6725 4675);
DISPLAY 0.489362 (-6725 4675);
PAINT SKYBLUE (-6725 4675);
FORCEPROP 1 LAST PART_NUMBER CH6104KEA00
J 0
(-6725 4475);
DISPLAY 0.489362 (-6725 4475);
PAINT SKYBLUE (-6725 4475);
FORCEPROP 1 LAST VOLTAGE 25V
J 0
(-6725 4625);
DISPLAY 0.489362 (-6725 4625);
PAINT SKYBLUE (-6725 4625);
FORCEPROP 1 LAST PACK_TYPE C0805
J 0
(-6725 4425);
DISPLAY 0.489362 (-6725 4425);
PAINT SKYBLUE (-6725 4425);
FORCEPROP 2 LAST CDS_LIB pure_quanta
J 0
(-6775 4625);
DISPLAY INVISIBLE (-6775 4625);
FORCEPROP 1 LAST PATH I22
J 0
(-6725 4775);
DISPLAY 0.978723 (-6725 4775);
PAINT WHITE (-6725 4775);
DISPLAY INVISIBLE (-6725 4775);
FORCEADD Q_CAP..1
(-6375 4625);
FORCEPROP 1 LAST LOCATION PC22
J 0
(-6325 4725);
DISPLAY 0.489362 (-6325 4725);
PAINT SKYBLUE (-6325 4725);
FORCEPROP 0 LAST $SEC 1
J 0
(-6325 4750);
DISPLAY 0.680851 (-6325 4750);
PAINT MONO (-6325 4750);
DISPLAY INVISIBLE (-6325 4750);
FORCEPROP 0 LAST CDS_SEC 1
J 0
(-6325 4750);
DISPLAY 1.021277 (-6325 4750);
DISPLAY INVISIBLE (-6325 4750);
FORCEPROP 1 LASTPIN (-6375 4725) $PN 1
J 0
(-6365 4705);
DISPLAY 0.489362 (-6365 4705);
PAINT MONO (-6365 4705);
FORCEPROP 1 LASTPIN (-6375 4525) $PN 2
J 0
(-6365 4505);
DISPLAY 0.489362 (-6365 4505);
PAINT MONO (-6365 4505);
FORCEPROP 1 LAST MATERIAL X7R
J 0
(-6325 4525);
DISPLAY 0.489362 (-6325 4525);
PAINT SKYBLUE (-6325 4525);
FORCEPROP 1 LAST TOLERANCE 10%
J 0
(-6325 4575);
DISPLAY 0.489362 (-6325 4575);
PAINT SKYBLUE (-6325 4575);
FORCEPROP 1 LAST VALUE 0.1UF
J 0
(-6325 4675);
DISPLAY 0.489362 (-6325 4675);
PAINT SKYBLUE (-6325 4675);
FORCEPROP 1 LAST PART_NUMBER CH4104K1B00
J 0
(-6325 4475);
DISPLAY 0.489362 (-6325 4475);
PAINT SKYBLUE (-6325 4475);
FORCEPROP 1 LAST VOLTAGE 25V
J 0
(-6325 4625);
DISPLAY 0.489362 (-6325 4625);
PAINT SKYBLUE (-6325 4625);
FORCEPROP 1 LAST PACK_TYPE 0402
J 0
(-6325 4425);
DISPLAY 0.489362 (-6325 4425);
PAINT SKYBLUE (-6325 4425);
FORCEPROP 2 LAST SIGNAL_MODEL DEFAULT_CAPACITOR_100000PF_2_1
J 0
(-6307 4895);
DISPLAY 1.021277 (-6307 4895);
DISPLAY INVISIBLE (-6307 4895);
FORCEPROP 2 LAST CDS_LIB pure_quanta
J 0
(-6375 4625);
PAINT MONO (-6375 4625);
DISPLAY INVISIBLE (-6375 4625);
FORCEPROP 1 LAST PATH I23
J 0
(-6325 4775);
DISPLAY 0.978723 (-6325 4775);
PAINT WHITE (-6325 4775);
DISPLAY INVISIBLE (-6325 4775);
FORCEPROP 2 LAST ROOM VR_CORE1_POWER_STAGE_1
J 1
(-6320 4751);
DISPLAY 1.021277 (-6320 4751);
PAINT RED (-6320 4751);
DISPLAY INVISIBLE (-6320 4751);
FORCEADD Q_RES..2
(-4425 4875);
FORCEPROP 1 LAST LOCATION PR9
J 0
(-4380 5000);
DISPLAY 0.489362 (-4380 5000);
PAINT SKYBLUE (-4380 5000);
FORCEPROP 2 LAST SEC 1
J 0
(-4374 5104);
DISPLAY 0.680851 (-4374 5104);
PAINT MONO (-4374 5104);
DISPLAY INVISIBLE (-4374 5104);
FORCEPROP 1 LASTPIN (-4425 4975) $PN 1
J 0
(-4420 4937);
DISPLAY 0.489362 (-4420 4937);
FORCEPROP 1 LASTPIN (-4425 4775) $PN 2
J 0
(-4420 4785);
DISPLAY 0.489362 (-4420 4785);
FORCEPROP 1 LAST WATTAGE 1/16W
J 0
(-4385 4850);
DISPLAY 0.489362 (-4385 4850);
PAINT SKYBLUE (-4385 4850);
FORCEPROP 1 LAST MATERIAL CHIP
J 0
(-4385 4800);
DISPLAY 0.489362 (-4385 4800);
PAINT SKYBLUE (-4385 4800);
FORCEPROP 1 LAST TOLERANCE 5%
J 0
(-4380 4900);
DISPLAY 0.489362 (-4380 4900);
PAINT SKYBLUE (-4380 4900);
FORCEPROP 1 LAST VALUE 10K
J 0
(-4380 4950);
DISPLAY 0.489362 (-4380 4950);
PAINT SKYBLUE (-4380 4950);
FORCEPROP 1 LAST PART_NUMBER TMP_QCS31002JB28
J 0
(-4385 4750);
DISPLAY 0.489362 (-4385 4750);
PAINT SKYBLUE (-4385 4750);
FORCEPROP 1 LAST PACK_TYPE 0402LF
J 0
(-4385 4700);
DISPLAY 0.489362 (-4385 4700);
PAINT SKYBLUE (-4385 4700);
FORCEPROP 2 LAST CDS_LIB pure_quanta
R 3
J 0
(-4425 4875);
PAINT MONO (-4425 4875);
DISPLAY INVISIBLE (-4425 4875);
FORCEPROP 2 LAST SEC_TYPE 0402LF
J 0
(-4374 5104);
DISPLAY 1.021277 (-4374 5104);
DISPLAY INVISIBLE (-4374 5104);
FORCEPROP 1 LAST PATH I24
J 0
(-4375 5050);
DISPLAY 0.978723 (-4375 5050);
PAINT WHITE (-4375 5050);
DISPLAY INVISIBLE (-4375 5050);
FORCEADD UNIVERSAL_POWER..1
(-4425 5150);
FORCEPROP 3 LASTPIN (-4425 5100) SIG_NAME P3V3_STBY\g
J 0
(-4415 5110);
DISPLAY 0.659574 (-4415 5110);
PAINT MONO (-4415 5110);
DISPLAY INVISIBLE (-4415 5110);
FORCEPROP 1 LAST HDL_POWER P3V3_STBY
J 1
(-4425 5200);
DISPLAY 0.489362 (-4425 5200);
PAINT GREEN (-4425 5200);
FORCEPROP 2 LAST CDS_LIB mstr_symbols
J 0
(-4425 5150);
DISPLAY INVISIBLE (-4425 5150);
FORCEPROP 1 LAST PATH I25
J 0
(-4375 5175);
DISPLAY 0.872340 (-4375 5175);
PAINT AQUA (-4375 5175);
DISPLAY INVISIBLE (-4375 5175);
FORCEADD Q_CAP..2
(-3325 3350);
FORCEPROP 1 LAST LOCATION PC64
J 1
(-3325 3450);
DISPLAY 0.489362 (-3325 3450);
PAINT SKYBLUE (-3325 3450);
FORCEPROP 0 LAST $SEC 1
J 0
(-3325 3500);
DISPLAY 0.680851 (-3325 3500);
PAINT MONO (-3325 3500);
DISPLAY INVISIBLE (-3325 3500);
FORCEPROP 0 LAST CDS_SEC 1
J 0
(-3325 3500);
DISPLAY 0.680851 (-3325 3500);
DISPLAY INVISIBLE (-3325 3500);
FORCEPROP 1 LASTPIN (-3425 3350) $PN 1
J 0
(-3435 3365);
DISPLAY 0.489362 (-3435 3365);
PAINT MONO (-3435 3365);
FORCEPROP 1 LASTPIN (-3225 3350) $PN 2
J 0
(-3240 3365);
DISPLAY 0.489362 (-3240 3365);
PAINT MONO (-3240 3365);
FORCEPROP 1 LAST MATERIAL X7R
J 0
(-3250 3300);
DISPLAY 0.489362 (-3250 3300);
PAINT SKYBLUE (-3250 3300);
FORCEPROP 1 LAST TOLERANCE 10%
J 2
(-3475 3250);
DISPLAY 0.489362 (-3475 3250);
PAINT SKYBLUE (-3475 3250);
FORCEPROP 1 LAST VALUE 220PF
J 2
(-3425 3400);
DISPLAY 0.489362 (-3425 3400);
PAINT SKYBLUE (-3425 3400);
FORCEPROP 1 LAST PART_NUMBER TMP_QCH12206KB14
J 1
(-3525 3300);
DISPLAY 0.489362 (-3525 3300);
PAINT SKYBLUE (-3525 3300);
FORCEPROP 1 LAST VOLTAGE 50V
J 0
(-3250 3400);
DISPLAY 0.489362 (-3250 3400);
PAINT SKYBLUE (-3250 3400);
FORCEPROP 1 LAST PACK_TYPE 0402
J 1
(-3225 3275);
DISPLAY 0.489362 (-3225 3275);
PAINT SKYBLUE (-3225 3275);
FORCEPROP 2 LAST CDS_LIB pure_quanta
J 0
(-3325 3350);
DISPLAY INVISIBLE (-3325 3350);
FORCEPROP 1 LAST PATH I26
J 0
(-3325 3550);
DISPLAY 0.978723 (-3325 3550);
PAINT WHITE (-3325 3550);
DISPLAY INVISIBLE (-3325 3550);
FORCEADD Q_RES..1
(-3325 3625);
FORCEPROP 1 LAST LOCATION PR148
J 0
(-3375 3675);
DISPLAY 0.489362 (-3375 3675);
PAINT SKYBLUE (-3375 3675);
FORCEPROP 2 LAST $SEC 1
J 0
(-3352 3838);
DISPLAY 0.680851 (-3352 3838);
PAINT MONO (-3352 3838);
DISPLAY INVISIBLE (-3352 3838);
FORCEPROP 2 LAST CDS_SEC 1
J 0
(-3352 3838);
DISPLAY 0.680851 (-3352 3838);
DISPLAY INVISIBLE (-3352 3838);
FORCEPROP 1 LASTPIN (-3425 3625) $PN 1
J 0
(-3413 3637);
DISPLAY 0.489362 (-3413 3637);
FORCEPROP 1 LASTPIN (-3225 3625) $PN 2
J 0
(-3263 3637);
DISPLAY 0.489362 (-3263 3637);
FORCEPROP 1 LAST MATERIAL CHIP
J 0
(-3150 3675);
DISPLAY 0.489362 (-3150 3675);
PAINT SKYBLUE (-3150 3675);
FORCEPROP 1 LAST VALUE 20K
J 2
(-3450 3675);
DISPLAY 0.489362 (-3450 3675);
PAINT SKYBLUE (-3450 3675);
FORCEPROP 1 LAST PART_NUMBER CS32002FB29
J 0
(-3575 3575);
DISPLAY 0.489362 (-3575 3575);
PAINT SKYBLUE (-3575 3575);
FORCEPROP 1 LAST PACK_TYPE 0402LF
J 0
(-3150 3575);
DISPLAY 0.489362 (-3150 3575);
PAINT SKYBLUE (-3150 3575);
FORCEPROP 2 LAST CDS_LIB pure_quanta
J 0
(-3325 3625);
DISPLAY INVISIBLE (-3325 3625);
FORCEPROP 1 LAST PATH I27
J 0
(-3375 3775);
DISPLAY 0.978723 (-3375 3775);
PAINT WHITE (-3375 3775);
DISPLAY INVISIBLE (-3375 3775);
FORCEPROP 1 LAST WATTAGE 1/16W
J 2
(-2751 3643);
DISPLAY 0.978723 (-2751 3643);
PAINT SKYBLUE (-2751 3643);
DISPLAY INVISIBLE (-2751 3643);
FORCEPROP 1 LAST TOLERANCE 1%
J 0
(-3205 3644);
DISPLAY 0.978723 (-3205 3644);
PAINT SKYBLUE (-3205 3644);
DISPLAY INVISIBLE (-3205 3644);
FORCEADD Q_INDUCTOR..1
(-3325 4100);
FORCEPROP 1 LAST LOCATION PL57
J 0
(-3450 4260);
DISPLAY 0.489362 (-3450 4260);
PAINT SKYBLUE (-3450 4260);
FORCEPROP 2 LAST $SEC 1
J 0
(-3450 4400);
DISPLAY 0.680851 (-3450 4400);
PAINT MONO (-3450 4400);
DISPLAY INVISIBLE (-3450 4400);
FORCEPROP 2 LAST CDS_SEC 1
J 0
(-3450 4400);
DISPLAY 0.680851 (-3450 4400);
DISPLAY INVISIBLE (-3450 4400);
FORCEPROP 2 LASTPIN (-3425 4075) $PN 1
J 2
(-3435 4085);
DISPLAY 0.489362 (-3435 4085);
FORCEPROP 2 LASTPIN (-3225 4075) $PN 2
J 0
(-3215 4085);
DISPLAY 0.489362 (-3215 4085);
FORCEPROP 1 LAST MATERIAL IND
J 0
(-3450 4155);
DISPLAY 0.489362 (-3450 4155);
PAINT SKYBLUE (-3450 4155);
FORCEPROP 2 LAST VALUE 1UH
J 0
(-3450 4300);
DISPLAY 0.489362 (-3450 4300);
PAINT SKYBLUE (-3450 4300);
FORCEPROP 1 LAST PART_NUMBER CV-10B0MZ13
J 0
(-3450 4210);
DISPLAY 0.489362 (-3450 4210);
PAINT SKYBLUE (-3450 4210);
FORCEPROP 2 LAST PACK_TYPE SMLF
J 0
(-3450 4350);
DISPLAY 0.489362 (-3450 4350);
PAINT SKYBLUE (-3450 4350);
FORCEPROP 2 LAST CDS_LIB pure_quanta
J 0
(-3325 4100);
DISPLAY INVISIBLE (-3325 4100);
FORCEPROP 1 LAST NEEDS_NO_SIZE TRUE
J 0
(-3325 4100);
DISPLAY 0.468085 (-3325 4100);
PAINT GREEN (-3325 4100);
DISPLAY INVISIBLE (-3325 4100);
FORCEPROP 1 LAST PATH I28
J 0
(-3250 4155);
DISPLAY 0.723404 (-3250 4155);
PAINT GREEN (-3250 4155);
DISPLAY INVISIBLE (-3250 4155);
FORCEADD Q_INDUCTOR..1
(-8500 4875);
FORCEPROP 1 LAST LOCATION PL26
J 0
(-8625 5035);
DISPLAY 0.489362 (-8625 5035);
PAINT SKYBLUE (-8625 5035);
FORCEPROP 0 LAST $SEC 1
J 0
(-8625 5175);
DISPLAY 0.680851 (-8625 5175);
PAINT MONO (-8625 5175);
DISPLAY INVISIBLE (-8625 5175);
FORCEPROP 0 LAST CDS_SEC 1
J 0
(-8625 5175);
DISPLAY 0.680851 (-8625 5175);
DISPLAY INVISIBLE (-8625 5175);
FORCEPROP 0 LASTPIN (-8600 4850) $PN 1
J 2
(-8610 4860);
DISPLAY 0.489362 (-8610 4860);
PAINT MONO (-8610 4860);
FORCEPROP 0 LASTPIN (-8400 4850) $PN 2
J 0
(-8390 4860);
DISPLAY 0.489362 (-8390 4860);
PAINT MONO (-8390 4860);
FORCEPROP 1 LAST MATERIAL IND
J 0
(-8625 4930);
DISPLAY 0.489362 (-8625 4930);
PAINT SKYBLUE (-8625 4930);
FORCEPROP 2 LAST VALUE BLM18SN220TN1D/8000MA
J 0
(-8625 5075);
DISPLAY 0.489362 (-8625 5075);
PAINT SKYBLUE (-8625 5075);
FORCEPROP 1 LAST PART_NUMBER CX220TN1001
J 0
(-8625 4985);
DISPLAY 0.489362 (-8625 4985);
PAINT SKYBLUE (-8625 4985);
FORCEPROP 2 LAST PACK_TYPE SMLF
J 0
(-8625 5125);
DISPLAY 0.489362 (-8625 5125);
PAINT SKYBLUE (-8625 5125);
FORCEPROP 1 LAST NEEDS_NO_SIZE TRUE
J 0
(-8500 4875);
DISPLAY 0.468085 (-8500 4875);
PAINT GREEN (-8500 4875);
DISPLAY INVISIBLE (-8500 4875);
FORCEPROP 2 LAST CDS_LIB pure_quanta
J 0
(-8500 4875);
DISPLAY INVISIBLE (-8500 4875);
FORCEPROP 1 LAST PATH I3
J 0
(-8425 4930);
DISPLAY 0.723404 (-8425 4930);
PAINT GREEN (-8425 4930);
DISPLAY INVISIBLE (-8425 4930);
FORCEADD P1V0..1
(0 4600);
FORCEPROP 3 LASTPIN (0 4550) SIG_NAME PVDD18_S5_P1\g
J 0
(10 4560);
DISPLAY 0.659574 (10 4560);
PAINT MONO (10 4560);
DISPLAY INVISIBLE (10 4560);
FORCEPROP 1 LAST HDL_POWER PVDD18_S5_P1
J 1
(0 4650);
DISPLAY 0.489362 (0 4650);
PAINT GREEN (0 4650);
FORCEPROP 2 LAST CDS_LIB pure_quanta_power
J 0
(0 4600);
PAINT MONO (0 4600);
DISPLAY INVISIBLE (0 4600);
FORCEPROP 1 LAST PATH I35
J 0
(50 4625);
DISPLAY 0.872340 (50 4625);
PAINT AQUA (50 4625);
DISPLAY INVISIBLE (50 4625);
FORCEADD Q_CAP..1
R 1
(-4325 3375);
FORCEPROP 1 LAST LOCATION PC62
J 0
(-4375 3425);
DISPLAY 0.489362 (-4375 3425);
PAINT SKYBLUE (-4375 3425);
FORCEPROP 0 LAST $SEC 1
R 1
J 0
(-4325 3450);
DISPLAY 0.680851 (-4325 3450);
PAINT MONO (-4325 3450);
DISPLAY INVISIBLE (-4325 3450);
FORCEPROP 0 LAST CDS_SEC 1
R 1
J 0
(-4325 3450);
DISPLAY 1.021277 (-4325 3450);
DISPLAY INVISIBLE (-4325 3450);
FORCEPROP 1 LASTPIN (-4425 3375) $PN 1
J 0
(-4405 3385);
DISPLAY 0.489362 (-4405 3385);
PAINT MONO (-4405 3385);
FORCEPROP 1 LASTPIN (-4225 3375) $PN 2
J 0
(-4285 3385);
DISPLAY 0.489362 (-4285 3385);
PAINT MONO (-4285 3385);
FORCEPROP 1 LAST MATERIAL X7R
J 0
(-4250 3325);
DISPLAY 0.489362 (-4250 3325);
PAINT SKYBLUE (-4250 3325);
FORCEPROP 1 LAST TOLERANCE 10%
J 0
(-4475 3275);
DISPLAY 0.489362 (-4475 3275);
PAINT SKYBLUE (-4475 3275);
FORCEPROP 1 LAST VALUE 0.1UF
J 0
(-4525 3425);
DISPLAY 0.489362 (-4525 3425);
PAINT SKYBLUE (-4525 3425);
FORCEPROP 1 LAST PART_NUMBER CH4104K1B00
J 0
(-4600 3325);
DISPLAY 0.489362 (-4600 3325);
PAINT SKYBLUE (-4600 3325);
FORCEPROP 1 LAST VOLTAGE 25V
J 0
(-4250 3425);
DISPLAY 0.489362 (-4250 3425);
PAINT SKYBLUE (-4250 3425);
FORCEPROP 1 LAST PACK_TYPE 0402
J 0
(-4250 3275);
DISPLAY 0.489362 (-4250 3275);
PAINT SKYBLUE (-4250 3275);
FORCEPROP 2 LAST CDS_LIB pure_quanta
R 1
J 0
(-4325 3375);
DISPLAY INVISIBLE (-4325 3375);
FORCEPROP 1 LAST PATH I37
R 1
J 0
(-4475 3425);
DISPLAY 0.978723 (-4475 3425);
PAINT WHITE (-4475 3425);
DISPLAY INVISIBLE (-4475 3425);
FORCEADD Q_RES..1
R 2
(-1500 3300);
FORCEPROP 1 LAST LOCATION PR402
J 2
(-1475 3325);
DISPLAY 0.489362 (-1475 3325);
PAINT SKYBLUE (-1475 3325);
FORCEPROP 0 LAST $SEC 1
J 0
(-1125 3350);
DISPLAY 0.680851 (-1125 3350);
PAINT MONO (-1125 3350);
DISPLAY INVISIBLE (-1125 3350);
FORCEPROP 0 LAST CDS_SEC 1
J 0
(-1125 3350);
DISPLAY 1.021277 (-1125 3350);
DISPLAY INVISIBLE (-1125 3350);
FORCEPROP 1 LASTPIN (-1400 3300) $PN 1
J 2
(-1412 3312);
DISPLAY 0.489362 (-1412 3312);
PAINT MONO (-1412 3312);
FORCEPROP 1 LASTPIN (-1600 3300) $PN 2
J 2
(-1562 3312);
DISPLAY 0.489362 (-1562 3312);
PAINT MONO (-1562 3312);
FORCEPROP 1 LAST WATTAGE 1/16W
J 0
(-1350 3325);
DISPLAY 0.489362 (-1350 3325);
PAINT SKYBLUE (-1350 3325);
FORCEPROP 1 LAST MATERIAL CHIP
J 2
(-1275 3200);
DISPLAY 0.489362 (-1275 3200);
PAINT SKYBLUE (-1275 3200);
FORCEPROP 1 LAST TOLERANCE 1%
J 2
(-1675 3200);
DISPLAY 0.489362 (-1675 3200);
PAINT SKYBLUE (-1675 3200);
FORCEPROP 1 LAST VALUE 49.9
J 0
(-1750 3350);
DISPLAY 0.489362 (-1750 3350);
PAINT SKYBLUE (-1750 3350);
FORCEPROP 1 LAST PART_NUMBER CS04992FB07
J 2
(-1575 3250);
DISPLAY 0.489362 (-1575 3250);
PAINT SKYBLUE (-1575 3250);
FORCEPROP 1 LAST PACK_TYPE 0402LF
J 2
(-1250 3250);
DISPLAY 0.489362 (-1250 3250);
PAINT SKYBLUE (-1250 3250);
FORCEPROP 2 LAST CDS_LIB pure_quanta
J 2
(-1500 3300);
DISPLAY INVISIBLE (-1500 3300);
FORCEPROP 1 LAST PATH I38
J 2
(-1450 3450);
DISPLAY 0.978723 (-1450 3450);
PAINT WHITE (-1450 3450);
DISPLAY INVISIBLE (-1450 3450);
FORCEADD Q_RES..1
R 1
(-3350 2425);
FORCEPROP 1 LAST LOCATION PR399
J 0
(-3300 2525);
DISPLAY 0.489362 (-3300 2525);
PAINT SKYBLUE (-3300 2525);
FORCEPROP 0 LAST $SEC 1
R 1
J 0
(-3300 2575);
DISPLAY 0.680851 (-3300 2575);
PAINT MONO (-3300 2575);
DISPLAY INVISIBLE (-3300 2575);
FORCEPROP 0 LAST CDS_SEC 1
R 1
J 0
(-3300 2575);
DISPLAY 1.021277 (-3300 2575);
DISPLAY INVISIBLE (-3300 2575);
FORCEPROP 1 LASTPIN (-3350 2325) $PN 1
J 0
(-3385 2360);
DISPLAY 0.489362 (-3385 2360);
PAINT MONO (-3385 2360);
FORCEPROP 1 LASTPIN (-3350 2525) $PN 2
J 0
(-3385 2485);
DISPLAY 0.489362 (-3385 2485);
PAINT MONO (-3385 2485);
FORCEPROP 1 LAST WATTAGE 1/16W
J 0
(-3300 2375);
DISPLAY 0.489362 (-3300 2375);
PAINT SKYBLUE (-3300 2375);
FORCEPROP 1 LAST MATERIAL CHIP
J 0
(-3300 2325);
DISPLAY 0.489362 (-3300 2325);
PAINT SKYBLUE (-3300 2325);
FORCEPROP 1 LAST TOLERANCE 1%
J 0
(-3300 2425);
DISPLAY 0.489362 (-3300 2425);
PAINT SKYBLUE (-3300 2425);
FORCEPROP 1 LAST VALUE 49.9
J 0
(-3300 2475);
DISPLAY 0.489362 (-3300 2475);
PAINT SKYBLUE (-3300 2475);
FORCEPROP 1 LAST PART_NUMBER CS04992FB07
J 0
(-3300 2275);
DISPLAY 0.489362 (-3300 2275);
PAINT SKYBLUE (-3300 2275);
FORCEPROP 1 LAST PACK_TYPE 0402LF
J 0
(-3300 2225);
DISPLAY 0.489362 (-3300 2225);
PAINT SKYBLUE (-3300 2225);
FORCEPROP 2 LAST CDS_LIB pure_quanta
R 1
J 0
(-3350 2425);
DISPLAY INVISIBLE (-3350 2425);
FORCEPROP 1 LAST PATH I39
R 1
J 0
(-3500 2375);
DISPLAY 0.978723 (-3500 2375);
PAINT WHITE (-3500 2375);
DISPLAY INVISIBLE (-3500 2375);
FORCEADD P1V0_AUX..1
(-8800 5200);
FORCEPROP 3 LASTPIN (-8800 5150) SIG_NAME P12V_STBY\g
J 0
(-8790 5160);
DISPLAY 0.659574 (-8790 5160);
PAINT MONO (-8790 5160);
DISPLAY INVISIBLE (-8790 5160);
FORCEPROP 1 LAST HDL_POWER P12V_STBY
J 1
(-8775 5250);
DISPLAY 0.489362 (-8775 5250);
PAINT GREEN (-8775 5250);
FORCEPROP 2 LAST CDS_LIB mstr_symbols
J 0
(-8800 5200);
DISPLAY INVISIBLE (-8800 5200);
FORCEPROP 1 LAST BODY_TYPE PLUMBING
J 0
(-8845 5157);
DISPLAY 0.340426 (-8845 5157);
PAINT GREEN (-8845 5157);
DISPLAY INVISIBLE (-8845 5157);
FORCEPROP 1 LAST PATH I4
J 0
(-8750 5225);
DISPLAY 0.872340 (-8750 5225);
PAINT AQUA (-8750 5225);
DISPLAY INVISIBLE (-8750 5225);
FORCEPROP 1 LAST VOLTAGE 1.0V
J 0
(-8845 5157);
DISPLAY 0.340426 (-8845 5157);
PAINT SKYBLUE (-8845 5157);
DISPLAY INVISIBLE (-8845 5157);
FORCEPROP 2 LAST ROOM VR_DDR1_POWER_STAGE
J 0
(-8800 5300);
DISPLAY 0.978723 (-8800 5300);
PAINT RED (-8800 5300);
DISPLAY INVISIBLE (-8800 5300);
FORCEADD OFFPAGE..1
R 2
(-775 2825);
FORCEPROP 2 LAST $XR0 54 
J 0
(-589 2825);
DISPLAY 0.638298 (-589 2825);
PAINT MONO (-589 2825);
FORCEPROP 2 LAST CDS_LIB standard
J 2
(-775 2825);
DISPLAY INVISIBLE (-775 2825);
FORCEPROP 1 LAST OFFPAGE TRUE
J 2
(-1100 2700);
DISPLAY 0.872340 (-1100 2700);
PAINT GREEN (-1100 2700);
DISPLAY INVISIBLE (-1100 2700);
FORCEPROP 1 LAST COMMENT_BODY TRUE
J 2
(-900 2725);
DISPLAY 0.872340 (-900 2725);
PAINT GREEN (-900 2725);
DISPLAY INVISIBLE (-900 2725);
FORCEPROP 2 LAST PATH I40
J 2
(-825 2900);
DISPLAY 1.021277 (-825 2900);
DISPLAY INVISIBLE (-825 2900);
FORCEADD OFFPAGE..1
R 2
(-775 2575);
FORCEPROP 2 LAST $XR0 54 
J 0
(-589 2575);
DISPLAY 0.638298 (-589 2575);
PAINT MONO (-589 2575);
FORCEPROP 2 LAST CDS_LIB standard
J 0
(-775 2575);
DISPLAY INVISIBLE (-775 2575);
FORCEPROP 1 LAST OFFPAGE TRUE
J 2
(-1100 2450);
DISPLAY 0.872340 (-1100 2450);
PAINT GREEN (-1100 2450);
DISPLAY INVISIBLE (-1100 2450);
FORCEPROP 1 LAST COMMENT_BODY TRUE
J 2
(-900 2475);
DISPLAY 0.872340 (-900 2475);
PAINT GREEN (-900 2475);
DISPLAY INVISIBLE (-900 2475);
FORCEPROP 2 LAST PATH I41
J 0
(-600 2650);
DISPLAY 1.021277 (-600 2650);
DISPLAY INVISIBLE (-600 2650);
FORCEADD Q_RES..2
R 1
(-2200 2575);
FORCEPROP 1 LAST LOCATION PR401
J 0
(-2200 2625);
DISPLAY 0.489362 (-2200 2625);
PAINT SKYBLUE (-2200 2625);
FORCEPROP 0 LAST $SEC 1
R 1
J 0
(-2075 2650);
DISPLAY 0.680851 (-2075 2650);
PAINT MONO (-2075 2650);
DISPLAY INVISIBLE (-2075 2650);
FORCEPROP 0 LAST CDS_SEC 1
R 1
J 0
(-2075 2650);
DISPLAY 1.021277 (-2075 2650);
DISPLAY INVISIBLE (-2075 2650);
FORCEPROP 1 LASTPIN (-2300 2575) $PN 1
J 0
(-2285 2585);
DISPLAY 0.489362 (-2285 2585);
PAINT MONO (-2285 2585);
FORCEPROP 1 LASTPIN (-2100 2575) $PN 2
J 0
(-2135 2585);
DISPLAY 0.489362 (-2135 2585);
PAINT MONO (-2135 2585);
FORCEPROP 1 LAST WATTAGE 1/16W
J 0
(-2075 2600);
DISPLAY 0.489362 (-2075 2600);
PAINT SKYBLUE (-2075 2600);
FORCEPROP 1 LAST MATERIAL CHIP
J 0
(-2075 2475);
DISPLAY 0.489362 (-2075 2475);
PAINT SKYBLUE (-2075 2475);
FORCEPROP 1 LAST TOLERANCE 5%
J 0
(-2375 2475);
DISPLAY 0.489362 (-2375 2475);
PAINT SKYBLUE (-2375 2475);
FORCEPROP 1 LAST VALUE 0
R 2
J 0
(-2375 2625);
DISPLAY 0.489362 (-2375 2625);
PAINT SKYBLUE (-2375 2625);
FORCEPROP 1 LAST PART_NUMBER CS00002JB38
J 0
(-2500 2525);
DISPLAY 0.489362 (-2500 2525);
PAINT SKYBLUE (-2500 2525);
FORCEPROP 1 LAST PACK_TYPE 0402LF
J 0
(-2100 2525);
DISPLAY 0.489362 (-2100 2525);
PAINT SKYBLUE (-2100 2525);
FORCEPROP 2 LAST CDS_LIB pure_quanta
R 1
J 0
(-2200 2575);
DISPLAY INVISIBLE (-2200 2575);
FORCEPROP 1 LAST PATH I42
R 1
J 0
(-2375 2625);
DISPLAY 0.978723 (-2375 2625);
PAINT WHITE (-2375 2625);
DISPLAY INVISIBLE (-2375 2625);
FORCEADD Q_RES..1
(-2200 2825);
FORCEPROP 1 LAST LOCATION PR400
J 0
(-2225 2875);
DISPLAY 0.489362 (-2225 2875);
PAINT SKYBLUE (-2225 2875);
FORCEPROP 0 LAST $SEC 1
J 0
(-2200 2900);
DISPLAY 0.680851 (-2200 2900);
PAINT MONO (-2200 2900);
DISPLAY INVISIBLE (-2200 2900);
FORCEPROP 0 LAST CDS_SEC 1
J 0
(-2200 2900);
DISPLAY 1.021277 (-2200 2900);
DISPLAY INVISIBLE (-2200 2900);
FORCEPROP 1 LASTPIN (-2300 2825) $PN 1
J 0
(-2288 2837);
DISPLAY 0.489362 (-2288 2837);
PAINT MONO (-2288 2837);
FORCEPROP 1 LASTPIN (-2100 2825) $PN 2
J 0
(-2138 2837);
DISPLAY 0.489362 (-2138 2837);
PAINT MONO (-2138 2837);
FORCEPROP 1 LAST WATTAGE 1/16W
J 2
(-1900 2850);
DISPLAY 0.489362 (-1900 2850);
PAINT SKYBLUE (-1900 2850);
FORCEPROP 1 LAST MATERIAL CHIP
J 0
(-2000 2725);
DISPLAY 0.489362 (-2000 2725);
PAINT SKYBLUE (-2000 2725);
FORCEPROP 1 LAST TOLERANCE 1%
J 0
(-2375 2725);
DISPLAY 0.489362 (-2375 2725);
PAINT SKYBLUE (-2375 2725);
FORCEPROP 1 LAST VALUE 10
J 2
(-2350 2850);
DISPLAY 0.489362 (-2350 2850);
PAINT SKYBLUE (-2350 2850);
FORCEPROP 1 LAST PART_NUMBER CS01002FB07
J 0
(-2500 2775);
DISPLAY 0.489362 (-2500 2775);
PAINT SKYBLUE (-2500 2775);
FORCEPROP 1 LAST PACK_TYPE 0402LF
J 0
(-2025 2775);
DISPLAY 0.489362 (-2025 2775);
PAINT SKYBLUE (-2025 2775);
FORCEPROP 2 LAST CDS_LIB pure_quanta
J 0
(-2200 2825);
DISPLAY INVISIBLE (-2200 2825);
FORCEPROP 1 LAST PATH I43
J 0
(-2250 2975);
DISPLAY 0.978723 (-2250 2975);
PAINT WHITE (-2250 2975);
DISPLAY INVISIBLE (-2250 2975);
FORCEADD UNIVERSAL_GND..1
(-3350 2200);
FORCEPROP 3 LASTPIN (-3350 2250) SIG_NAME GND\g
J 0
(-3340 2260);
DISPLAY 0.659574 (-3340 2260);
PAINT MONO (-3340 2260);
DISPLAY INVISIBLE (-3340 2260);
FORCEPROP 2 LAST CDS_LIB pure_quanta_power
J 0
(-3350 2200);
DISPLAY INVISIBLE (-3350 2200);
FORCEPROP 1 LAST PATH I44
J 0
(-3275 2200);
DISPLAY 0.872340 (-3275 2200);
PAINT AQUA (-3275 2200);
DISPLAY INVISIBLE (-3275 2200);
FORCEPROP 1 LAST HDL_POWER GND
J 1
(-3325 2125);
DISPLAY 0.872340 (-3325 2125);
PAINT GREEN (-3325 2125);
DISPLAY INVISIBLE (-3325 2125);
FORCEADD UNIVERSAL_GND..1
(0 3525);
FORCEPROP 3 LASTPIN (0 3575) SIG_NAME GND\g
J 0
(10 3585);
DISPLAY 0.659574 (10 3585);
PAINT MONO (10 3585);
DISPLAY INVISIBLE (10 3585);
FORCEPROP 2 LAST CDS_LIB pure_quanta_power
J 0
(0 3525);
DISPLAY INVISIBLE (0 3525);
FORCEPROP 1 LAST PATH I45
J 0
(75 3525);
DISPLAY 0.872340 (75 3525);
PAINT AQUA (75 3525);
DISPLAY INVISIBLE (75 3525);
FORCEPROP 1 LAST HDL_POWER GND
J 1
(25 3450);
DISPLAY 0.872340 (25 3450);
PAINT GREEN (25 3450);
DISPLAY INVISIBLE (25 3450);
FORCEADD Q_CAP..1
(-1300 3825);
FORCEPROP 1 LAST LOCATION PC88
J 0
(-1250 3925);
DISPLAY 0.489362 (-1250 3925);
PAINT SKYBLUE (-1250 3925);
FORCEPROP 0 LAST $SEC 1
J 0
(-1250 3950);
DISPLAY 0.680851 (-1250 3950);
PAINT MONO (-1250 3950);
DISPLAY INVISIBLE (-1250 3950);
FORCEPROP 0 LAST CDS_SEC 1
J 0
(-1250 3950);
DISPLAY 1.021277 (-1250 3950);
DISPLAY INVISIBLE (-1250 3950);
FORCEPROP 1 LASTPIN (-1300 3925) $PN 1
J 0
(-1290 3905);
DISPLAY 0.489362 (-1290 3905);
PAINT MONO (-1290 3905);
FORCEPROP 1 LASTPIN (-1300 3725) $PN 2
J 0
(-1290 3705);
DISPLAY 0.489362 (-1290 3705);
PAINT MONO (-1290 3705);
FORCEPROP 1 LAST MATERIAL EMPTY
J 0
(-1250 3725);
DISPLAY 0.489362 (-1250 3725);
PAINT RED (-1250 3725);
FORCEPROP 1 LAST TOLERANCE 20%
J 0
(-1250 3775);
DISPLAY 0.489362 (-1250 3775);
PAINT SKYBLUE (-1250 3775);
FORCEPROP 1 LAST VALUE 22UF
J 0
(-1250 3875);
DISPLAY 0.489362 (-1250 3875);
PAINT SKYBLUE (-1250 3875);
FORCEPROP 1 LAST VOLTAGE 4V
J 0
(-1250 3825);
DISPLAY 0.489362 (-1250 3825);
PAINT SKYBLUE (-1250 3825);
FORCEPROP 1 LAST PACK_TYPE 0805
J 0
(-1250 3675);
DISPLAY 0.489362 (-1250 3675);
PAINT SKYBLUE (-1250 3675);
FORCEPROP 2 LAST CDS_LIB pure_quanta
J 0
(-1300 3825);
DISPLAY INVISIBLE (-1300 3825);
FORCEPROP 1 LAST PATH I48
J 0
(-1250 3975);
DISPLAY 0.978723 (-1250 3975);
PAINT WHITE (-1250 3975);
DISPLAY INVISIBLE (-1250 3975);
FORCEPROP 1 LAST PART_NUMBER TMP_QCH622KMEA01
J 0
(-1250 3675);
DISPLAY 0.489362 (-1250 3675);
PAINT SKYBLUE (-1250 3675);
DISPLAY INVISIBLE (-1250 3675);
FORCEADD Q_CAP..1
(-1625 3825);
FORCEPROP 1 LAST LOCATION PC87
J 0
(-1575 3925);
DISPLAY 0.489362 (-1575 3925);
PAINT SKYBLUE (-1575 3925);
FORCEPROP 0 LAST $SEC 1
J 0
(-1575 3950);
DISPLAY 0.680851 (-1575 3950);
PAINT MONO (-1575 3950);
DISPLAY INVISIBLE (-1575 3950);
FORCEPROP 0 LAST CDS_SEC 1
J 0
(-1575 3950);
DISPLAY 1.021277 (-1575 3950);
DISPLAY INVISIBLE (-1575 3950);
FORCEPROP 1 LASTPIN (-1625 3925) $PN 1
J 0
(-1615 3905);
DISPLAY 0.489362 (-1615 3905);
PAINT MONO (-1615 3905);
FORCEPROP 1 LASTPIN (-1625 3725) $PN 2
J 0
(-1615 3705);
DISPLAY 0.489362 (-1615 3705);
PAINT MONO (-1615 3705);
FORCEPROP 1 LAST MATERIAL EMPTY
J 0
(-1575 3725);
DISPLAY 0.489362 (-1575 3725);
PAINT RED (-1575 3725);
FORCEPROP 1 LAST TOLERANCE 20%
J 0
(-1575 3775);
DISPLAY 0.489362 (-1575 3775);
PAINT SKYBLUE (-1575 3775);
FORCEPROP 1 LAST VALUE 22UF
J 0
(-1575 3875);
DISPLAY 0.489362 (-1575 3875);
PAINT SKYBLUE (-1575 3875);
FORCEPROP 1 LAST VOLTAGE 4V
J 0
(-1575 3825);
DISPLAY 0.489362 (-1575 3825);
PAINT SKYBLUE (-1575 3825);
FORCEPROP 1 LAST PACK_TYPE 0805
J 0
(-1575 3675);
DISPLAY 0.489362 (-1575 3675);
PAINT SKYBLUE (-1575 3675);
FORCEPROP 2 LAST CDS_LIB pure_quanta
J 0
(-1625 3825);
DISPLAY INVISIBLE (-1625 3825);
FORCEPROP 1 LAST PATH I49
J 0
(-1575 3975);
DISPLAY 0.978723 (-1575 3975);
PAINT WHITE (-1575 3975);
DISPLAY INVISIBLE (-1575 3975);
FORCEPROP 1 LAST PART_NUMBER TMP_QCH622KMEA01
J 0
(-1575 3675);
DISPLAY 0.489362 (-1575 3675);
PAINT SKYBLUE (-1575 3675);
DISPLAY INVISIBLE (-1575 3675);
FORCEADD UNIVERSAL_GND..1
(-6925 2825);
FORCEPROP 3 LASTPIN (-6925 2875) SIG_NAME GND\g
J 0
(-6915 2885);
DISPLAY 0.659574 (-6915 2885);
PAINT MONO (-6915 2885);
DISPLAY INVISIBLE (-6915 2885);
FORCEPROP 2 LAST CDS_LIB pure_quanta_power
J 0
(-6925 2825);
DISPLAY INVISIBLE (-6925 2825);
FORCEPROP 1 LAST PATH I5
J 0
(-6850 2825);
DISPLAY 0.872340 (-6850 2825);
PAINT AQUA (-6850 2825);
DISPLAY INVISIBLE (-6850 2825);
FORCEPROP 1 LAST HDL_POWER GND
J 1
(-6900 2750);
DISPLAY 0.872340 (-6900 2750);
PAINT GREEN (-6900 2750);
DISPLAY INVISIBLE (-6900 2750);
FORCEADD Q_CAP..1
(-1875 3825);
FORCEPROP 1 LAST LOCATION PC84
J 0
(-1825 3925);
DISPLAY 0.489362 (-1825 3925);
PAINT SKYBLUE (-1825 3925);
FORCEPROP 0 LAST $SEC 1
J 0
(-1825 3950);
DISPLAY 0.680851 (-1825 3950);
PAINT MONO (-1825 3950);
DISPLAY INVISIBLE (-1825 3950);
FORCEPROP 0 LAST CDS_SEC 1
J 0
(-1825 3950);
DISPLAY 1.021277 (-1825 3950);
DISPLAY INVISIBLE (-1825 3950);
FORCEPROP 1 LASTPIN (-1875 3925) $PN 1
J 0
(-1865 3905);
DISPLAY 0.489362 (-1865 3905);
PAINT MONO (-1865 3905);
FORCEPROP 1 LASTPIN (-1875 3725) $PN 2
J 0
(-1865 3705);
DISPLAY 0.489362 (-1865 3705);
PAINT MONO (-1865 3705);
FORCEPROP 1 LAST MATERIAL X6S
J 0
(-1825 3725);
DISPLAY 0.489362 (-1825 3725);
PAINT SKYBLUE (-1825 3725);
FORCEPROP 1 LAST TOLERANCE 20%
J 0
(-1825 3775);
DISPLAY 0.489362 (-1825 3775);
PAINT SKYBLUE (-1825 3775);
FORCEPROP 1 LAST VALUE 22UF
J 0
(-1825 3875);
DISPLAY 0.489362 (-1825 3875);
PAINT SKYBLUE (-1825 3875);
FORCEPROP 1 LAST VOLTAGE 4V
J 0
(-1825 3825);
DISPLAY 0.489362 (-1825 3825);
PAINT SKYBLUE (-1825 3825);
FORCEPROP 1 LAST PACK_TYPE 0805
J 0
(-1825 3675);
DISPLAY 0.489362 (-1825 3675);
PAINT SKYBLUE (-1825 3675);
FORCEPROP 2 LAST CDS_LIB pure_quanta
J 0
(-1875 3825);
DISPLAY INVISIBLE (-1875 3825);
FORCEPROP 1 LAST PATH I50
J 0
(-1825 3975);
DISPLAY 0.978723 (-1825 3975);
PAINT WHITE (-1825 3975);
DISPLAY INVISIBLE (-1825 3975);
FORCEPROP 1 LAST PART_NUMBER TMP_QCH622KMEA01
J 0
(-1825 3675);
DISPLAY 0.489362 (-1825 3675);
PAINT SKYBLUE (-1825 3675);
DISPLAY INVISIBLE (-1825 3675);
FORCEADD Q_CAP..1
(-2075 3825);
FORCEPROP 1 LAST LOCATION PC83
J 0
(-2025 3925);
DISPLAY 0.489362 (-2025 3925);
PAINT SKYBLUE (-2025 3925);
FORCEPROP 0 LAST $SEC 1
J 0
(-2025 3950);
DISPLAY 0.680851 (-2025 3950);
PAINT MONO (-2025 3950);
DISPLAY INVISIBLE (-2025 3950);
FORCEPROP 0 LAST CDS_SEC 1
J 0
(-2025 3950);
DISPLAY 1.021277 (-2025 3950);
DISPLAY INVISIBLE (-2025 3950);
FORCEPROP 1 LASTPIN (-2075 3925) $PN 1
J 0
(-2065 3905);
DISPLAY 0.489362 (-2065 3905);
PAINT MONO (-2065 3905);
FORCEPROP 1 LASTPIN (-2075 3725) $PN 2
J 0
(-2065 3705);
DISPLAY 0.489362 (-2065 3705);
PAINT MONO (-2065 3705);
FORCEPROP 1 LAST MATERIAL X6S
J 0
(-2025 3725);
DISPLAY 0.489362 (-2025 3725);
PAINT SKYBLUE (-2025 3725);
FORCEPROP 1 LAST TOLERANCE 20%
J 0
(-2025 3775);
DISPLAY 0.489362 (-2025 3775);
PAINT SKYBLUE (-2025 3775);
FORCEPROP 1 LAST VALUE 22UF
J 0
(-2025 3875);
DISPLAY 0.489362 (-2025 3875);
PAINT SKYBLUE (-2025 3875);
FORCEPROP 1 LAST VOLTAGE 4V
J 0
(-2025 3825);
DISPLAY 0.489362 (-2025 3825);
PAINT SKYBLUE (-2025 3825);
FORCEPROP 1 LAST PACK_TYPE 0805
J 0
(-2025 3675);
DISPLAY 0.489362 (-2025 3675);
PAINT SKYBLUE (-2025 3675);
FORCEPROP 2 LAST CDS_LIB pure_quanta
J 0
(-2075 3825);
DISPLAY INVISIBLE (-2075 3825);
FORCEPROP 1 LAST PATH I51
J 0
(-2025 3975);
DISPLAY 0.978723 (-2025 3975);
PAINT WHITE (-2025 3975);
DISPLAY INVISIBLE (-2025 3975);
FORCEPROP 1 LAST PART_NUMBER TMP_QCH622KMEA01
J 0
(-2025 3675);
DISPLAY 0.489362 (-2025 3675);
PAINT SKYBLUE (-2025 3675);
DISPLAY INVISIBLE (-2025 3675);
FORCEADD Q_CAP..1
(-2500 3825);
FORCEPROP 1 LAST LOCATION PC65
J 0
(-2450 3925);
DISPLAY 0.489362 (-2450 3925);
PAINT SKYBLUE (-2450 3925);
FORCEPROP 0 LAST $SEC 1
J 0
(-2450 3950);
DISPLAY 0.680851 (-2450 3950);
PAINT MONO (-2450 3950);
DISPLAY INVISIBLE (-2450 3950);
FORCEPROP 0 LAST CDS_SEC 1
J 0
(-2450 3950);
DISPLAY 1.021277 (-2450 3950);
DISPLAY INVISIBLE (-2450 3950);
FORCEPROP 1 LASTPIN (-2500 3925) $PN 1
J 0
(-2490 3905);
DISPLAY 0.489362 (-2490 3905);
PAINT MONO (-2490 3905);
FORCEPROP 1 LASTPIN (-2500 3725) $PN 2
J 0
(-2490 3705);
DISPLAY 0.489362 (-2490 3705);
PAINT MONO (-2490 3705);
FORCEPROP 1 LAST MATERIAL X6S
J 0
(-2450 3725);
DISPLAY 0.489362 (-2450 3725);
PAINT SKYBLUE (-2450 3725);
FORCEPROP 1 LAST TOLERANCE 20%
J 0
(-2450 3775);
DISPLAY 0.489362 (-2450 3775);
PAINT SKYBLUE (-2450 3775);
FORCEPROP 1 LAST VALUE 22UF
J 0
(-2450 3875);
DISPLAY 0.489362 (-2450 3875);
PAINT SKYBLUE (-2450 3875);
FORCEPROP 1 LAST PART_NUMBER TMP_QCH622KMEA01
J 0
(-2450 3675);
DISPLAY 0.489362 (-2450 3675);
PAINT SKYBLUE (-2450 3675);
FORCEPROP 1 LAST VOLTAGE 4V
J 0
(-2450 3825);
DISPLAY 0.489362 (-2450 3825);
PAINT SKYBLUE (-2450 3825);
FORCEPROP 1 LAST PACK_TYPE 0805
J 0
(-2450 3625);
DISPLAY 0.489362 (-2450 3625);
PAINT SKYBLUE (-2450 3625);
FORCEPROP 2 LAST CDS_LIB pure_quanta
J 0
(-2500 3825);
DISPLAY INVISIBLE (-2500 3825);
FORCEPROP 1 LAST PATH I52
J 0
(-2450 3975);
DISPLAY 0.978723 (-2450 3975);
PAINT WHITE (-2450 3975);
DISPLAY INVISIBLE (-2450 3975);
FORCEADD Q_CAP..1
(-8075 4625);
FORCEPROP 1 LAST LOCATION PC60
J 0
(-8025 4725);
DISPLAY 0.489362 (-8025 4725);
PAINT SKYBLUE (-8025 4725);
FORCEPROP 0 LAST $SEC 1
J 0
(-8025 4750);
DISPLAY 0.680851 (-8025 4750);
PAINT MONO (-8025 4750);
DISPLAY INVISIBLE (-8025 4750);
FORCEPROP 0 LAST CDS_SEC 1
J 0
(-8025 4750);
DISPLAY 1.021277 (-8025 4750);
DISPLAY INVISIBLE (-8025 4750);
FORCEPROP 1 LASTPIN (-8075 4725) $PN 1
J 0
(-8065 4705);
DISPLAY 0.489362 (-8065 4705);
PAINT MONO (-8065 4705);
FORCEPROP 1 LASTPIN (-8075 4525) $PN 2
J 0
(-8065 4505);
DISPLAY 0.489362 (-8065 4505);
PAINT MONO (-8065 4505);
FORCEPROP 1 LAST MATERIAL X6S
J 0
(-8025 4525);
DISPLAY 0.489362 (-8025 4525);
PAINT SKYBLUE (-8025 4525);
FORCEPROP 1 LAST TOLERANCE 10%
J 0
(-8025 4575);
DISPLAY 0.489362 (-8025 4575);
PAINT SKYBLUE (-8025 4575);
FORCEPROP 1 LAST VALUE 10UF
J 0
(-8025 4675);
DISPLAY 0.489362 (-8025 4675);
PAINT SKYBLUE (-8025 4675);
FORCEPROP 1 LAST PART_NUMBER CH6104KEA00
J 0
(-8025 4475);
DISPLAY 0.489362 (-8025 4475);
PAINT SKYBLUE (-8025 4475);
FORCEPROP 1 LAST PACK_TYPE C0805
J 0
(-8025 4425);
DISPLAY 0.489362 (-8025 4425);
PAINT SKYBLUE (-8025 4425);
FORCEPROP 1 LAST VOLTAGE 25V
J 0
(-8025 4625);
DISPLAY 0.489362 (-8025 4625);
PAINT SKYBLUE (-8025 4625);
FORCEPROP 2 LAST CDS_LIB pure_quanta
J 0
(-8075 4625);
DISPLAY INVISIBLE (-8075 4625);
FORCEPROP 1 LAST PATH I53
J 0
(-8025 4775);
DISPLAY 0.978723 (-8025 4775);
PAINT WHITE (-8025 4775);
DISPLAY INVISIBLE (-8025 4775);
FORCEADD Q_RES..2
(0 3825);
FORCEPROP 1 LAST LOCATION PR403
J 0
(45 3950);
DISPLAY 0.489362 (45 3950);
PAINT SKYBLUE (45 3950);
FORCEPROP 0 LAST $SEC 1
J 0
(50 3975);
DISPLAY 0.680851 (50 3975);
PAINT MONO (50 3975);
DISPLAY INVISIBLE (50 3975);
FORCEPROP 0 LAST CDS_SEC 1
J 0
(50 3975);
DISPLAY 1.021277 (50 3975);
DISPLAY INVISIBLE (50 3975);
FORCEPROP 1 LASTPIN (0 3925) $PN 1
J 0
(5 3887);
DISPLAY 0.489362 (5 3887);
PAINT MONO (5 3887);
FORCEPROP 1 LASTPIN (0 3725) $PN 2
J 0
(5 3735);
DISPLAY 0.489362 (5 3735);
PAINT MONO (5 3735);
FORCEPROP 1 LAST WATTAGE 1/16W
J 0
(40 3800);
DISPLAY 0.489362 (40 3800);
PAINT SKYBLUE (40 3800);
FORCEPROP 1 LAST MATERIAL CHIP
J 0
(40 3750);
DISPLAY 0.489362 (40 3750);
PAINT SKYBLUE (40 3750);
FORCEPROP 1 LAST TOLERANCE 1%
J 0
(45 3850);
DISPLAY 0.489362 (45 3850);
PAINT SKYBLUE (45 3850);
FORCEPROP 1 LAST VALUE 1K
J 0
(45 3900);
DISPLAY 0.489362 (45 3900);
PAINT SKYBLUE (45 3900);
FORCEPROP 1 LAST PART_NUMBER TMP_QCS21002FB24
J 0
(40 3700);
DISPLAY 0.489362 (40 3700);
PAINT SKYBLUE (40 3700);
FORCEPROP 1 LAST PACK_TYPE 0402LF
J 0
(40 3650);
DISPLAY 0.489362 (40 3650);
PAINT SKYBLUE (40 3650);
FORCEPROP 2 LAST CDS_LIB pure_quanta
J 0
(0 3825);
DISPLAY INVISIBLE (0 3825);
FORCEPROP 1 LAST PATH I55
J 0
(50 4000);
DISPLAY 0.978723 (50 4000);
PAINT WHITE (50 4000);
DISPLAY INVISIBLE (50 4000);
FORCEADD Q_RES..1
(-6900 3875);
FORCEPROP 1 LAST LOCATION PR398
J 0
(-6950 3925);
DISPLAY 0.489362 (-6950 3925);
PAINT SKYBLUE (-6950 3925);
FORCEPROP 0 LAST $SEC 1
J 0
(-6950 3950);
DISPLAY 0.680851 (-6950 3950);
PAINT MONO (-6950 3950);
DISPLAY INVISIBLE (-6950 3950);
FORCEPROP 0 LAST CDS_SEC 1
J 0
(-6950 3950);
DISPLAY 1.021277 (-6950 3950);
DISPLAY INVISIBLE (-6950 3950);
FORCEPROP 1 LASTPIN (-7000 3875) $PN 1
J 0
(-6988 3887);
DISPLAY 0.489362 (-6988 3887);
PAINT MONO (-6988 3887);
FORCEPROP 1 LASTPIN (-6800 3875) $PN 2
J 0
(-6838 3887);
DISPLAY 0.489362 (-6838 3887);
PAINT MONO (-6838 3887);
FORCEPROP 1 LAST WATTAGE 1/16W
J 0
(-6825 3775);
DISPLAY 0.489362 (-6825 3775);
PAINT SKYBLUE (-6825 3775);
FORCEPROP 1 LAST MATERIAL CHIP
J 0
(-7200 3775);
DISPLAY 0.489362 (-7200 3775);
PAINT SKYBLUE (-7200 3775);
FORCEPROP 1 LAST TOLERANCE 5%
J 0
(-6775 3900);
DISPLAY 0.489362 (-6775 3900);
PAINT SKYBLUE (-6775 3900);
FORCEPROP 1 LAST VALUE 0
J 2
(-7075 3900);
DISPLAY 0.489362 (-7075 3900);
PAINT SKYBLUE (-7075 3900);
FORCEPROP 1 LAST PART_NUMBER CS00002JB38
J 0
(-7200 3800);
DISPLAY 0.489362 (-7200 3800);
PAINT SKYBLUE (-7200 3800);
FORCEPROP 1 LAST PACK_TYPE 0402LF
J 0
(-6825 3800);
DISPLAY 0.489362 (-6825 3800);
PAINT SKYBLUE (-6825 3800);
FORCEPROP 2 LAST CDS_LIB pure_quanta
J 0
(-6900 3875);
DISPLAY INVISIBLE (-6900 3875);
FORCEPROP 1 LAST PATH I56
J 0
(-6950 4025);
DISPLAY 0.978723 (-6950 4025);
PAINT WHITE (-6950 4025);
DISPLAY INVISIBLE (-6950 4025);
FORCEADD UNIVERSAL_GND..1
(-7500 3525);
FORCEPROP 3 LASTPIN (-7500 3575) SIG_NAME GND\g
J 0
(-7490 3585);
DISPLAY 0.659574 (-7490 3585);
PAINT MONO (-7490 3585);
DISPLAY INVISIBLE (-7490 3585);
FORCEPROP 2 LAST CDS_LIB pure_quanta_power
J 0
(-7500 3525);
DISPLAY INVISIBLE (-7500 3525);
FORCEPROP 1 LAST PATH I57
J 0
(-7425 3525);
DISPLAY 0.872340 (-7425 3525);
PAINT AQUA (-7425 3525);
DISPLAY INVISIBLE (-7425 3525);
FORCEPROP 1 LAST HDL_POWER GND
J 1
(-7475 3450);
DISPLAY 0.872340 (-7475 3450);
PAINT GREEN (-7475 3450);
DISPLAY INVISIBLE (-7475 3450);
FORCEADD Q_CAPP..1
(-1025 3800);
FORCEPROP 1 LAST LOCATION PC89
J 0
(-975 3925);
DISPLAY 0.489362 (-975 3925);
PAINT SKYBLUE (-975 3925);
FORCEPROP 0 LAST $SEC 1
J 0
(-975 3975);
DISPLAY 0.680851 (-975 3975);
PAINT MONO (-975 3975);
DISPLAY INVISIBLE (-975 3975);
FORCEPROP 0 LAST CDS_SEC 1
J 0
(-975 3975);
DISPLAY 1.021277 (-975 3975);
DISPLAY INVISIBLE (-975 3975);
FORCEPROP 1 LASTPIN (-1025 3900) $PN 1
J 0
(-1015 3885);
DISPLAY 0.489362 (-1015 3885);
PAINT MONO (-1015 3885);
FORCEPROP 1 LASTPIN (-1025 3700) $PN 2
J 0
(-1015 3685);
DISPLAY 0.489362 (-1015 3685);
PAINT MONO (-1015 3685);
FORCEPROP 1 LAST MATERIAL OSCON
J 0
(-975 3725);
DISPLAY 0.489362 (-975 3725);
PAINT SKYBLUE (-975 3725);
FORCEPROP 1 LAST TOLERANCE 20%
J 0
(-975 3825);
DISPLAY 0.489362 (-975 3825);
PAINT SKYBLUE (-975 3825);
FORCEPROP 1 LAST VALUE 390UF
J 0
(-975 3875);
DISPLAY 0.489362 (-975 3875);
PAINT SKYBLUE (-975 3875);
FORCEPROP 1 LAST PART_NUMBER CC7390JMZ12
J 0
(-975 3625);
DISPLAY 0.489362 (-975 3625);
PAINT SKYBLUE (-975 3625);
FORCEPROP 1 LAST VOLTAGE 2.5V
J 0
(-975 3775);
DISPLAY 0.489362 (-975 3775);
PAINT SKYBLUE (-975 3775);
FORCEPROP 1 LAST PACK_TYPE SMLF
J 0
(-975 3675);
DISPLAY 0.489362 (-975 3675);
PAINT SKYBLUE (-975 3675);
FORCEPROP 2 LAST CDS_LIB pure_quanta
J 0
(-1025 3800);
DISPLAY INVISIBLE (-1025 3800);
FORCEPROP 1 LAST PATH I59
J 0
(-975 3950);
DISPLAY 0.978723 (-975 3950);
DISPLAY INVISIBLE (-975 3950);
FORCEADD Q_CAP..1
R 2
(-6925 3110);
FORCEPROP 1 LAST LOCATION PC20
J 0
(-6875 3208);
DISPLAY 0.489362 (-6875 3208);
PAINT SKYBLUE (-6875 3208);
FORCEPROP 2 LAST SEC 1
J 0
(-6975 3306);
DISPLAY 0.680851 (-6975 3306);
PAINT MONO (-6975 3306);
DISPLAY INVISIBLE (-6975 3306);
FORCEPROP 1 LASTPIN (-6925 3210) $PN 1
J 2
(-6879 3181);
DISPLAY 0.489362 (-6879 3181);
FORCEPROP 1 LASTPIN (-6925 3010) $PN 2
J 2
(-6881 3005);
DISPLAY 0.489362 (-6881 3005);
FORCEPROP 1 LAST MATERIAL X6S
J 0
(-6875 3024);
DISPLAY 0.489362 (-6875 3024);
PAINT SKYBLUE (-6875 3024);
FORCEPROP 1 LAST TOLERANCE 10%
J 0
(-6875 3073);
DISPLAY 0.489362 (-6875 3073);
PAINT SKYBLUE (-6875 3073);
FORCEPROP 1 LAST VALUE 1UF
J 0
(-6875 3171);
DISPLAY 0.489362 (-6875 3171);
PAINT SKYBLUE (-6875 3171);
FORCEPROP 1 LAST PART_NUMBER CH5104KEB02
J 0
(-6875 2926);
DISPLAY 0.489362 (-6875 2926);
PAINT SKYBLUE (-6875 2926);
FORCEPROP 1 LAST VOLTAGE 25V
J 0
(-6875 3122);
DISPLAY 0.489362 (-6875 3122);
PAINT SKYBLUE (-6875 3122);
FORCEPROP 1 LAST PACK_TYPE C0402
J 0
(-6875 2975);
DISPLAY 0.489362 (-6875 2975);
PAINT SKYBLUE (-6875 2975);
FORCEPROP 2 LAST CDS_LIB pure_quanta
J 0
(-6925 3110);
DISPLAY INVISIBLE (-6925 3110);
FORCEPROP 2 LAST SIGNAL_MODEL DEFAULT_CAPACITOR_100000PF_2_1
R 3
J 1
(-6995 3058);
DISPLAY 0.744681 (-6995 3058);
PAINT MONO (-6995 3058);
DISPLAY INVISIBLE (-6995 3058);
FORCEPROP 2 LAST SEC_TYPE C0402
J 0
(-6975 3306);
DISPLAY 1.021277 (-6975 3306);
DISPLAY INVISIBLE (-6975 3306);
FORCEPROP 1 LAST PATH I6
J 2
(-6975 3260);
DISPLAY 0.978723 (-6975 3260);
PAINT WHITE (-6975 3260);
DISPLAY INVISIBLE (-6975 3260);
FORCEPROP 2 LAST ROOM VR_DDR0_CTRL
R 3
J 1
(-6981 3071);
DISPLAY 0.744681 (-6981 3071);
PAINT RED (-6981 3071);
DISPLAY INVISIBLE (-6981 3071);
FORCEADD Q_CAP..1
(-650 3800);
FORCEPROP 1 LAST LOCATION PC21
J 0
(-600 3925);
DISPLAY 0.489362 (-600 3925);
PAINT SKYBLUE (-600 3925);
FORCEPROP 0 LAST $SEC 1
J 0
(-600 3925);
DISPLAY 0.680851 (-600 3925);
PAINT MONO (-600 3925);
DISPLAY INVISIBLE (-600 3925);
FORCEPROP 0 LAST CDS_SEC 1
J 0
(-600 3925);
DISPLAY 1.021277 (-600 3925);
DISPLAY INVISIBLE (-600 3925);
FORCEPROP 1 LASTPIN (-650 3900) $PN 1
J 0
(-640 3880);
DISPLAY 0.489362 (-640 3880);
PAINT MONO (-640 3880);
FORCEPROP 1 LASTPIN (-650 3700) $PN 2
J 0
(-640 3680);
DISPLAY 0.489362 (-640 3680);
PAINT MONO (-640 3680);
FORCEPROP 1 LAST MATERIAL X7R
J 0
(-600 3725);
DISPLAY 0.489362 (-600 3725);
PAINT SKYBLUE (-600 3725);
FORCEPROP 1 LAST TOLERANCE 10%
J 0
(-600 3775);
DISPLAY 0.489362 (-600 3775);
PAINT SKYBLUE (-600 3775);
FORCEPROP 1 LAST VALUE 0.1UF
J 0
(-600 3875);
DISPLAY 0.489362 (-600 3875);
PAINT SKYBLUE (-600 3875);
FORCEPROP 1 LAST PART_NUMBER CH4104K1B00
J 0
(-600 3675);
DISPLAY 0.489362 (-600 3675);
PAINT SKYBLUE (-600 3675);
FORCEPROP 1 LAST VOLTAGE 25V
J 0
(-600 3825);
DISPLAY 0.489362 (-600 3825);
PAINT SKYBLUE (-600 3825);
FORCEPROP 1 LAST PACK_TYPE 0402
J 0
(-600 3625);
DISPLAY 0.489362 (-600 3625);
PAINT SKYBLUE (-600 3625);
FORCEPROP 2 LAST CDS_LIB pure_quanta
J 0
(-650 3800);
DISPLAY INVISIBLE (-650 3800);
FORCEPROP 1 LAST PATH I60
J 0
(-600 3950);
DISPLAY 0.978723 (-600 3950);
PAINT WHITE (-600 3950);
DISPLAY INVISIBLE (-600 3950);
FORCEADD UNIVERSAL_GND..1
(-650 3450);
FORCEPROP 3 LASTPIN (-650 3500) SIG_NAME GND\g
J 0
(-640 3510);
DISPLAY 0.659574 (-640 3510);
PAINT MONO (-640 3510);
DISPLAY INVISIBLE (-640 3510);
FORCEPROP 2 LAST CDS_LIB pure_quanta_power
J 0
(-650 3450);
DISPLAY INVISIBLE (-650 3450);
FORCEPROP 1 LAST PATH I61
J 0
(-575 3450);
DISPLAY 0.872340 (-575 3450);
PAINT AQUA (-575 3450);
DISPLAY INVISIBLE (-575 3450);
FORCEPROP 1 LAST HDL_POWER GND
J 1
(-625 3375);
DISPLAY 0.872340 (-625 3375);
PAINT GREEN (-625 3375);
DISPLAY INVISIBLE (-625 3375);
FORCEADD Q_RES..1
(-3625 4575);
FORCEPROP 1 LAST LOCATION R259
J 0
(-3500 4575);
DISPLAY 0.489362 (-3500 4575);
PAINT SKYBLUE (-3500 4575);
FORCEPROP 0 LAST $SEC 1
J 2
(-3500 4625);
DISPLAY 0.680851 (-3500 4625);
PAINT MONO (-3500 4625);
DISPLAY INVISIBLE (-3500 4625);
FORCEPROP 0 LAST CDS_SEC 1
J 2
(-3500 4625);
DISPLAY 1.021277 (-3500 4625);
DISPLAY INVISIBLE (-3500 4625);
FORCEPROP 1 LASTPIN (-3725 4575) $PN 1
J 0
(-3713 4587);
DISPLAY 0.489362 (-3713 4587);
PAINT MONO (-3713 4587);
FORCEPROP 1 LASTPIN (-3525 4575) $PN 2
J 0
(-3563 4587);
DISPLAY 0.489362 (-3563 4587);
PAINT MONO (-3563 4587);
FORCEPROP 1 LAST VALUE 33
J 2
(-3750 4575);
DISPLAY 0.489362 (-3750 4575);
PAINT SKYBLUE (-3750 4575);
FORCEPROP 2 LAST BOM_COST MEM
J 2
(-3600 4725);
DISPLAY 0.744681 (-3600 4725);
PAINT WHITE (-3600 4725);
DISPLAY INVISIBLE (-3600 4725);
FORCEPROP 2 LAST CDS_LIB pure_quanta
J 2
(-3625 4575);
DISPLAY INVISIBLE (-3625 4575);
FORCEPROP 1 LAST PATH I62
J 0
(-3675 4725);
DISPLAY 0.978723 (-3675 4725);
PAINT WHITE (-3675 4725);
DISPLAY INVISIBLE (-3675 4725);
FORCEPROP 1 LAST WATTAGE 1/16W
J 2
(-3700 4500);
DISPLAY 0.489362 (-3700 4500);
PAINT SKYBLUE (-3700 4500);
DISPLAY INVISIBLE (-3700 4500);
FORCEPROP 1 LAST MATERIAL CHIP
J 2
(-3450 4550);
DISPLAY 0.489362 (-3450 4550);
PAINT SKYBLUE (-3450 4550);
DISPLAY INVISIBLE (-3450 4550);
FORCEPROP 1 LAST TOLERANCE 5%
J 0
(-3750 4550);
DISPLAY 0.489362 (-3750 4550);
PAINT SKYBLUE (-3750 4550);
DISPLAY INVISIBLE (-3750 4550);
FORCEPROP 1 LAST PART_NUMBER CS03302JB29
J 2
(-3525 4625);
DISPLAY 0.489362 (-3525 4625);
PAINT SKYBLUE (-3525 4625);
DISPLAY INVISIBLE (-3525 4625);
FORCEPROP 1 LAST PACK_TYPE 0402LF
J 2
(-3450 4500);
DISPLAY 0.489362 (-3450 4500);
PAINT SKYBLUE (-3450 4500);
DISPLAY INVISIBLE (-3450 4500);
FORCEPROP 2 LAST ROOM RST_CPU0_PLD_TO_DIMM
J 2
(-3600 4675);
DISPLAY 0.744681 (-3600 4675);
PAINT RED (-3600 4675);
DISPLAY INVISIBLE (-3600 4675);
FORCEADD OFFPAGE..2
(-2775 4575);
FORCEPROP 2 LAST $XR0 80 
J 0
(-2586 4575);
DISPLAY 0.638298 (-2586 4575);
PAINT MONO (-2586 4575);
FORCEPROP 2 LAST CDS_LIB standard
J 0
(-2775 4575);
DISPLAY INVISIBLE (-2775 4575);
FORCEPROP 1 LAST OFFPAGE TRUE
J 0
(-2450 4450);
DISPLAY 1.170213 (-2450 4450);
PAINT GREEN (-2450 4450);
DISPLAY INVISIBLE (-2450 4450);
FORCEPROP 1 LAST COMMENT_BODY TRUE
J 0
(-2820 4480);
DISPLAY 1.170213 (-2820 4480);
PAINT GREEN (-2820 4480);
DISPLAY INVISIBLE (-2820 4480);
FORCEPROP 2 LAST PATH I63
J 0
(-2575 4625);
DISPLAY 0.680851 (-2575 4625);
DISPLAY INVISIBLE (-2575 4625);
FORCEPROP 2 LAST ROOM VR_CORE0_CTRL
J 2
(-2500 4625);
PAINT RED (-2500 4625);
DISPLAY INVISIBLE (-2500 4625);
FORCEADD Q_CAP..1
R 2
(-7775 3925);
FORCEPROP 1 LAST LOCATION C675
J 2
(-7825 4025);
DISPLAY 0.489362 (-7825 4025);
PAINT SKYBLUE (-7825 4025);
FORCEPROP 0 LAST $SEC 1
J 0
(-7825 4075);
DISPLAY 0.680851 (-7825 4075);
PAINT MONO (-7825 4075);
DISPLAY INVISIBLE (-7825 4075);
FORCEPROP 0 LAST CDS_SEC 1
J 0
(-7825 4075);
DISPLAY 0.680851 (-7825 4075);
DISPLAY INVISIBLE (-7825 4075);
FORCEPROP 1 LASTPIN (-7775 4025) $PN 1
J 2
(-7785 4005);
DISPLAY 0.489362 (-7785 4005);
PAINT MONO (-7785 4005);
FORCEPROP 1 LASTPIN (-7775 3825) $PN 2
J 2
(-7785 3805);
DISPLAY 0.489362 (-7785 3805);
PAINT MONO (-7785 3805);
FORCEPROP 1 LAST MATERIAL EMPTY
J 2
(-7825 3825);
DISPLAY 0.489362 (-7825 3825);
PAINT RED (-7825 3825);
FORCEPROP 1 LAST TOLERANCE 10%
J 2
(-7825 3875);
DISPLAY 0.489362 (-7825 3875);
PAINT SKYBLUE (-7825 3875);
FORCEPROP 1 LAST VALUE 0.1UF
J 2
(-7825 3975);
DISPLAY 0.489362 (-7825 3975);
PAINT SKYBLUE (-7825 3975);
FORCEPROP 1 LAST PART_NUMBER CH4104K1B00
J 2
(-7850 3775);
DISPLAY 0.489362 (-7850 3775);
PAINT SKYBLUE (-7850 3775);
FORCEPROP 1 LAST VOLTAGE 25V
J 2
(-7825 3925);
DISPLAY 0.489362 (-7825 3925);
PAINT SKYBLUE (-7825 3925);
FORCEPROP 1 LAST PACK_TYPE 0402
J 2
(-7825 3725);
DISPLAY 0.489362 (-7825 3725);
PAINT SKYBLUE (-7825 3725);
FORCEPROP 2 LAST CDS_LIB pure_quanta
J 0
(-7775 3925);
DISPLAY INVISIBLE (-7775 3925);
FORCEPROP 1 LAST PATH I64
J 2
(-7825 4075);
DISPLAY 0.978723 (-7825 4075);
PAINT WHITE (-7825 4075);
DISPLAY INVISIBLE (-7825 4075);
FORCEPROP 2 LAST ROOM VR_DDR0_CTRL
R 3
J 1
(-7831 3886);
DISPLAY 0.744681 (-7831 3886);
PAINT RED (-7831 3886);
DISPLAY INVISIBLE (-7831 3886);
FORCEADD UNIVERSAL_GND..1
(-7775 3725);
FORCEPROP 3 LASTPIN (-7775 3775) SIG_NAME GND\g
J 0
(-7765 3785);
DISPLAY 0.659574 (-7765 3785);
PAINT MONO (-7765 3785);
DISPLAY INVISIBLE (-7765 3785);
FORCEPROP 2 LAST CDS_LIB pure_quanta_power
J 0
(-7775 3725);
DISPLAY INVISIBLE (-7775 3725);
FORCEPROP 1 LAST PATH I65
J 0
(-7700 3725);
DISPLAY 0.872340 (-7700 3725);
PAINT AQUA (-7700 3725);
DISPLAY INVISIBLE (-7700 3725);
FORCEPROP 1 LAST HDL_POWER GND
J 1
(-7750 3650);
DISPLAY 0.872340 (-7750 3650);
PAINT GREEN (-7750 3650);
DISPLAY INVISIBLE (-7750 3650);
FORCEADD UNIVERSAL_GND..1
(-7800 4250);
FORCEPROP 3 LASTPIN (-7800 4300) SIG_NAME GND\g
J 0
(-7790 4310);
DISPLAY 0.659574 (-7790 4310);
PAINT MONO (-7790 4310);
DISPLAY INVISIBLE (-7790 4310);
FORCEPROP 2 LAST CDS_LIB pure_quanta_power
J 0
(-7800 4250);
DISPLAY INVISIBLE (-7800 4250);
FORCEPROP 1 LAST PATH I7
J 0
(-7725 4250);
DISPLAY 0.872340 (-7725 4250);
PAINT AQUA (-7725 4250);
DISPLAY INVISIBLE (-7725 4250);
FORCEPROP 1 LAST HDL_POWER GND
J 1
(-7775 4175);
DISPLAY 0.872340 (-7775 4175);
PAINT GREEN (-7775 4175);
DISPLAY INVISIBLE (-7775 4175);
FORCEADD Q_RES..2
(-6925 3475);
FORCEPROP 1 LAST LOCATION PR397
J 0
(-6880 3600);
DISPLAY 0.489362 (-6880 3600);
PAINT SKYBLUE (-6880 3600);
FORCEPROP 0 LAST $SEC 1
J 0
(-6875 3650);
DISPLAY 0.680851 (-6875 3650);
PAINT MONO (-6875 3650);
DISPLAY INVISIBLE (-6875 3650);
FORCEPROP 0 LAST CDS_SEC 1
J 0
(-6875 3650);
DISPLAY 1.021277 (-6875 3650);
DISPLAY INVISIBLE (-6875 3650);
FORCEPROP 1 LASTPIN (-6925 3575) $PN 1
J 0
(-6920 3537);
DISPLAY 0.489362 (-6920 3537);
PAINT MONO (-6920 3537);
FORCEPROP 1 LASTPIN (-6925 3375) $PN 2
J 0
(-6920 3385);
DISPLAY 0.489362 (-6920 3385);
PAINT MONO (-6920 3385);
FORCEPROP 1 LAST WATTAGE 1/16W
J 0
(-6885 3450);
DISPLAY 0.489362 (-6885 3450);
PAINT SKYBLUE (-6885 3450);
FORCEPROP 1 LAST MATERIAL CHIP
J 0
(-6885 3400);
DISPLAY 0.489362 (-6885 3400);
PAINT SKYBLUE (-6885 3400);
FORCEPROP 1 LAST TOLERANCE 5%
J 0
(-6880 3500);
DISPLAY 0.489362 (-6880 3500);
PAINT SKYBLUE (-6880 3500);
FORCEPROP 1 LAST VALUE 0
J 0
(-6880 3550);
DISPLAY 0.489362 (-6880 3550);
PAINT SKYBLUE (-6880 3550);
FORCEPROP 1 LAST PART_NUMBER CS00002JB38
J 0
(-6885 3350);
DISPLAY 0.489362 (-6885 3350);
PAINT SKYBLUE (-6885 3350);
FORCEPROP 1 LAST PACK_TYPE 0402LF
J 0
(-6885 3300);
DISPLAY 0.489362 (-6885 3300);
PAINT SKYBLUE (-6885 3300);
FORCEPROP 2 LAST CDS_LIB pure_quanta
J 0
(-6925 3475);
DISPLAY INVISIBLE (-6925 3475);
FORCEPROP 1 LAST PATH I8
J 0
(-6875 3650);
DISPLAY 0.978723 (-6875 3650);
PAINT WHITE (-6875 3650);
DISPLAY INVISIBLE (-6875 3650);
FORCEADD UNIVERSAL_POWER..1
(-6925 3675);
FORCEPROP 3 LASTPIN (-6925 3625) SIG_NAME P3V3_STBY\g
J 0
(-6915 3635);
DISPLAY 0.659574 (-6915 3635);
PAINT MONO (-6915 3635);
DISPLAY INVISIBLE (-6915 3635);
FORCEPROP 1 LAST HDL_POWER P3V3_STBY
J 1
(-6925 3725);
DISPLAY 0.489362 (-6925 3725);
PAINT GREEN (-6925 3725);
FORCEPROP 2 LAST CDS_LIB mstr_symbols
J 0
(-6925 3675);
PAINT MONO (-6925 3675);
DISPLAY INVISIBLE (-6925 3675);
FORCEPROP 1 LAST PATH I9
J 0
(-6875 3700);
DISPLAY 0.872340 (-6875 3700);
PAINT AQUA (-6875 3700);
DISPLAY INVISIBLE (-6875 3700);
FORCEADD QUANTA_TITLE_BLOCK_C..1
(425 550);
FORCEPROP 0 LAST CDS_CON_LAST_MODIFIED Fri Mar 11 14:53:21 2022
J 0
(-1460 565);
DISPLAY INVISIBLE (-1460 565);
FORCEPROP 1 LAST CUSTOM_TXT_CDS <CON_LAST_MODIFIED>
J 0
(-1460 565);
DISPLAY 0.978723 (-1460 565);
FORCEPROP 2 LAST CUSTOM_TXT_CDS <XR_PAGE_TITLE>
J 0
(-7465 5800);
DISPLAY 0.638298 (-7465 5800);
PAINT PINK (-7465 5800);
DISPLAY INVISIBLE (-7465 5800);
FORCEPROP 1 LAST CUSTOM_TXT_CDS <NAME_2>
J 0
(-2750 600);
FORCEPROP 1 LAST CUSTOM_TXT_CDS <NAME_1>
J 0
(-2750 725);
FORCEPROP 1 LAST CUSTOM_TXT_CDS <Q_NUMBER>
J 0
(-978 653);
DISPLAY 1.212766 (-978 653);
FORCEPROP 1 LAST CUSTOM_TXT_CDS <Q_PROJ>
J 0
(-1957 652);
DISPLAY 1.212766 (-1957 652);
FORCEPROP 1 LAST CUSTOM_TXT_CDS <Q_REV>
J 0
(241 653);
DISPLAY 1.212766 (241 653);
FORCEPROP 1 LAST CUSTOM_TXT_CDS <CON_PAGE_NUM> OF <CON_TOTAL_PAGES>
J 0
(-21 568);
DISPLAY 0.978723 (-21 568);
FORCEPROP 1 LAST Q_DEPT BU9
J 1
(-3338 599);
DISPLAY 1.957447 (-3338 599);
PAINT GREEN (-3338 599);
FORCEPROP 1 LAST Q_TITLE PVDD18_S5_P1
J 0
(-8875 600);
DISPLAY 2.446809 (-8875 600);
PAINT GREEN (-8875 600);
FORCEPROP 2 LAST CDS_LIB pure_quanta
J 0
(425 550);
DISPLAY INVISIBLE (425 550);
FORCEPROP 1 LAST CDS_LMAN_SYM_OUTLINE -9475,6775,100,-125
J 0
(425 550);
DISPLAY 0.468085 (425 550);
PAINT GREEN (425 550);
DISPLAY INVISIBLE (425 550);
FORCEPROP 2 LAST PAGE_BORDER TRUE
J 0
(-7465 5800);
DISPLAY 0.638298 (-7465 5800);
PAINT PINK (-7465 5800);
DISPLAY INVISIBLE (-7465 5800);
FORCEPROP 1 LAST COMMENT_BODY TRUE
J 0
(437 537);
DISPLAY 0.978723 (437 537);
PAINT GREEN (437 537);
DISPLAY INVISIBLE (437 537);
FORCEPROP 2 LAST CDS_XR_PAGE_TITLE CR-202 : @T6G_MB_LIB.T6G(SCH_1):PAGE202
J 0
(-7465 5800);
DISPLAY 0.638298 (-7465 5800);
PAINT PINK (-7465 5800);
DISPLAY INVISIBLE (-7465 5800);
FORCEADD DNS..1
(-1275 3825);
PAINT RED (-1275 3825);
FORCEPROP 2 LAST CDS_LIB mstr_misc
J 0
(-1275 3825);
DISPLAY INVISIBLE (-1275 3825);
FORCEPROP 1 LAST COMMENT_BODY TRUE
R 1
J 0
(-1200 3600);
DISPLAY 0.872340 (-1200 3600);
PAINT GREEN (-1200 3600);
DISPLAY INVISIBLE (-1200 3600);
FORCEADD DNS..1
(-1575 3825);
PAINT RED (-1575 3825);
FORCEPROP 2 LAST CDS_LIB mstr_misc
J 0
(-1575 3825);
DISPLAY INVISIBLE (-1575 3825);
FORCEPROP 1 LAST COMMENT_BODY TRUE
R 1
J 0
(-1500 3600);
DISPLAY 0.872340 (-1500 3600);
PAINT GREEN (-1500 3600);
DISPLAY INVISIBLE (-1500 3600);
FORCEADD DNS..1
(-7800 3825);
PAINT RED (-7800 3825);
FORCEPROP 2 LAST CDS_LIB mstr_misc
J 0
(-7800 3825);
DISPLAY INVISIBLE (-7800 3825);
FORCEPROP 1 LAST COMMENT_BODY TRUE
J 0
(-7800 3825);
DISPLAY INVISIBLE (-7800 3825);
WIRE 16 -1 (-6425 2950)(-6425 2850);
WIRE 16 -1 (-4750 3000)(-4750 3100);
WIRE 16 -1 (-4425 5100)(-4425 4975);
WIRE 16 -1 (-3350 2325)(-3350 2250);
WIRE 16 -1 (0 3575)(0 3725);
WIRE 16 -1 (-6925 2875)(-6925 3010);
WIRE 16 -1 (-7000 3875)(-7500 3875);
WIRE 16 -1 (-7500 3875)(-7500 3575);
WIRE 16 -1 (-7775 3775)(-7775 3825);
WIRE 16 -1 (-6925 3625)(-6925 3575);
WIRE 17 273 (-8750 2250)(-6575 2250);
WIRE 17 273 (-8750 2650)(-8750 2250);
WIRE 17 273 (-6575 2650)(-6575 2250);
WIRE 17 273 (-8750 2650)(-6575 2650);
WIRE 17 273 (-8750 1500)(-6575 1500);
WIRE 17 273 (-8750 2100)(-8750 1500);
WIRE 17 273 (-6575 2100)(-6575 1500);
WIRE 17 273 (-8750 2100)(-6575 2100);
WIRE 16 -1 (-8800 5150)(-8800 4850);
WIRE 16 -1 (-8600 4850)(-8800 4850);
WIRE 16 -1 (-6925 3210)(-6925 3275);
WIRE 16 -1 (-6925 3275)(-6600 3275);
WIRE 16 -1 (-6925 3375)(-6925 3275);
WIRE 16 -1 (-6600 3275)(-6600 3625);
WIRE 16 -1 (-5875 3625)(-6600 3625);
FORCEPROP 2 LAST SIG_NAME PVDD18_S5_P1_VCC
J 0
(-6160 3635);
DISPLAY 0.489362 (-6160 3635);
FORCEPROP 2 LASTPROP $XRERR UNIQUE?
J 0
(-6400 3635);
DISPLAY 0.638298 (-6400 3635);
PAINT MONO (-6400 3635);
DISPLAY INVISIBLE (-6400 3635);
WIRE 16 -1 (-6425 3150)(-6425 3275);
FORCEPROP 2 LAST SIG_NAME PVDD18_S5_P1_CS
J 0
(-6285 3300);
DISPLAY 0.489362 (-6285 3300);
FORCEPROP 2 LASTPROP $XRERR UNIQUE?
J 0
(-6525 3300);
DISPLAY 0.638298 (-6525 3300);
PAINT MONO (-6525 3300);
DISPLAY INVISIBLE (-6525 3300);
WIRE 16 -1 (-6425 3275)(-5875 3275);
WIRE 16 -1 (-5875 3875)(-6800 3875);
FORCEPROP 2 LAST SIG_NAME PVDD18_S5_P1_MODE
J 0
(-6685 3885);
DISPLAY 0.489362 (-6685 3885);
FORCEPROP 2 LASTPROP $XRERR UNIQUE?
J 0
(-6925 3885);
DISPLAY 0.638298 (-6925 3885);
PAINT MONO (-6925 3885);
DISPLAY INVISIBLE (-6925 3885);
WIRE 16 -1 (-8525 4075)(-7775 4075);
FORCEPROP 2 LAST SIG_NAME PVDD18_S5_P1_EN
J 0
(-8485 4085);
DISPLAY 0.489362 (-8485 4085);
WIRE 16 -1 (-7775 4075)(-5875 4075);
WIRE 16 -1 (-7775 4075)(-7775 4025);
WIRE 16 -1 (-4925 3225)(-4925 3275);
WIRE 16 -1 (-4925 3000)(-4925 3225);
WIRE 16 -1 (-5075 3225)(-4925 3225);
WIRE 16 -1 (-4925 3275)(-5075 3275);
WIRE 16 -1 (-5075 3375)(-4750 3375);
FORCEPROP 2 LAST SIG_NAME PVDD18_S5_P1_REF
J 0
(-4985 3385);
DISPLAY 0.489362 (-4985 3385);
FORCEPROP 2 LASTPROP $XRERR UNIQUE?
J 0
(-5225 3385);
DISPLAY 0.638298 (-5225 3385);
PAINT MONO (-5225 3385);
DISPLAY INVISIBLE (-5225 3385);
WIRE 16 -1 (-4425 3375)(-4750 3375);
WIRE 16 -1 (-4750 3300)(-4750 3375);
WIRE 16 -1 (-8075 4525)(-8075 4403);
WIRE 16 -1 (-8075 4403)(-7800 4403);
WIRE 16 -1 (-7800 4403)(-7625 4403);
WIRE 16 -1 (-7800 4300)(-7800 4403);
WIRE 16 -1 (-7625 4403)(-7225 4403);
WIRE 16 -1 (-7625 4525)(-7625 4403);
WIRE 16 -1 (-7225 4403)(-6775 4403);
WIRE 16 -1 (-7225 4525)(-7225 4403);
WIRE 16 -1 (-6375 4403)(-6775 4403);
WIRE 16 -1 (-6775 4525)(-6775 4403);
WIRE 16 -1 (-6375 4525)(-6375 4403);
WIRE 16 -1 (-8400 4850)(-8075 4850);
WIRE 16 -1 (-8075 4850)(-7625 4850);
WIRE 16 -1 (-8075 4725)(-8075 4850);
WIRE 16 -1 (-7625 4850)(-7225 4850);
FORCEPROP 2 LAST SIG_NAME SW_P12V_STBY_PVDD18_S5_P1_FLT
J 0
(-7237 4873);
DISPLAY 0.489362 (-7237 4873);
FORCEPROP 2 LASTPROP $XRERR UNIQUE?
J 0
(-7477 4873);
DISPLAY 0.638298 (-7477 4873);
PAINT MONO (-7477 4873);
DISPLAY INVISIBLE (-7477 4873);
WIRE 16 -1 (-7625 4725)(-7625 4850);
WIRE 16 -1 (-7225 4850)(-6775 4850);
WIRE 16 -1 (-7225 4725)(-7225 4850);
WIRE 16 -1 (-6775 4850)(-6375 4850);
WIRE 16 -1 (-6775 4725)(-6775 4850);
WIRE 16 -1 (-6375 4850)(-6050 4850);
WIRE 16 -1 (-6375 4725)(-6375 4850);
WIRE 16 -1 (-6050 4850)(-6050 4575);
WIRE 16 -1 (-6050 4575)(-5875 4575);
WIRE 16 -1 (-6050 4575)(-6050 4525);
WIRE 16 -1 (-6050 4525)(-5875 4525);
WIRE 16 -1 (-5075 4375)(-4200 4375);
FORCEPROP 2 LAST SIG_NAME SW_PVDD18_S5_P1_BST
J 0
(-4985 4400);
DISPLAY 0.489362 (-4985 4400);
FORCEPROP 2 LASTPROP $XRERR UNIQUE?
J 0
(-5225 4400);
DISPLAY 0.638298 (-5225 4400);
PAINT MONO (-5225 4400);
DISPLAY INVISIBLE (-5225 4400);
WIRE 16 -1 (-4200 4325)(-4200 4375);
WIRE 16 -1 (-5075 4075)(-4200 4075);
FORCEPROP 2 LAST SIG_NAME SW_PVDD18_S5_P1_SW
J 0
(-4970 4092);
DISPLAY 0.489362 (-4970 4092);
FORCEPROP 2 LASTPROP $XRERR UNIQUE?
J 0
(-5210 4092);
DISPLAY 0.638298 (-5210 4092);
PAINT MONO (-5210 4092);
DISPLAY INVISIBLE (-5210 4092);
WIRE 16 -1 (-4200 4075)(-3425 4075);
WIRE 16 -1 (-4200 4125)(-4200 4075);
WIRE 16 -1 (-5075 4575)(-4425 4575);
WIRE 16 -1 (-4425 4575)(-3725 4575);
FORCEPROP 2 LAST SIG_NAME PWRGD_PVDD18_S5_P1
J 0
(-4260 4585);
DISPLAY 0.489362 (-4260 4585);
FORCEPROP 2 LASTPROP $XRERR UNIQUE?
J 0
(-4500 4585);
DISPLAY 0.638298 (-4500 4585);
PAINT MONO (-4500 4585);
DISPLAY INVISIBLE (-4500 4585);
WIRE 16 -1 (-4425 4775)(-4425 4575);
WIRE 16 -1 (-3232 2347)(-3232 2348);
WIRE 16 -1 (-3350 2525)(-3350 2575);
WIRE 16 -1 (-2300 2575)(-3350 2575);
WIRE 16 -1 (-3350 2575)(-3925 2575);
WIRE 16 -1 (-3925 2575)(-3925 3025);
WIRE 16 -1 (-3925 3225)(-3925 3025);
WIRE 16 -1 (-4050 3025)(-3925 3025);
WIRE 16 -1 (-4050 3375)(-4050 3025);
WIRE 16 -1 (-4225 3375)(-4050 3375);
WIRE 16 -1 (-4050 3475)(-4050 3375);
WIRE 16 -1 (-5075 3475)(-4050 3475);
FORCEPROP 2 LAST SIG_NAME PVDD18_SS_P1_RGND
J 0
(-4985 3485);
DISPLAY 0.489362 (-4985 3485);
FORCEPROP 2 LASTPROP $XRERR UNIQUE?
J 0
(-5225 3485);
DISPLAY 0.638298 (-5225 3485);
PAINT MONO (-5225 3485);
DISPLAY INVISIBLE (-5225 3485);
WIRE 16 -1 (-5075 3625)(-3925 3625);
FORCEPROP 2 LAST SIG_NAME PVDD18_S5_P1_FB
J 0
(-4985 3650);
DISPLAY 0.489362 (-4985 3650);
FORCEPROP 2 LASTPROP $XRERR UNIQUE?
J 0
(-5225 3650);
DISPLAY 0.638298 (-5225 3650);
PAINT MONO (-5225 3650);
DISPLAY INVISIBLE (-5225 3650);
WIRE 16 -1 (-3700 3625)(-3925 3625);
WIRE 16 -1 (-3925 3425)(-3925 3625);
WIRE 16 -1 (-3425 3625)(-3700 3625);
WIRE 16 -1 (-3700 3625)(-3700 3350);
WIRE 16 -1 (-3425 3350)(-3700 3350);
WIRE 16 -1 (-2319 2826)(-2319 2827);
WIRE 16 -1 (-2650 3300)(-1600 3300);
FORCEPROP 2 LAST SIG_NAME PVDD18_S5_P1_FB_RC
J 0
(-2360 3310);
DISPLAY 0.489362 (-2360 3310);
FORCEPROP 2 LASTPROP $XRERR UNIQUE?
J 0
(-2600 3310);
DISPLAY 0.638298 (-2600 3310);
PAINT MONO (-2600 3310);
DISPLAY INVISIBLE (-2600 3310);
WIRE 16 -1 (-2650 3625)(-2650 3300);
WIRE 16 -1 (-2800 3625)(-2650 3625);
WIRE 16 -1 (-2800 2825)(-2800 3625);
WIRE 16 -1 (-2975 3625)(-2800 3625);
WIRE 16 -1 (-3225 3625)(-2975 3625);
WIRE 16 -1 (-2975 3350)(-2975 3625);
WIRE 16 -1 (-2800 2825)(-2300 2825);
WIRE 16 -1 (-2975 3350)(-3225 3350);
WIRE 16 -1 (-2500 3725)(-2500 3575);
WIRE 16 -1 (-2500 3575)(-2075 3575);
WIRE 16 -1 (-2075 3575)(-1875 3575);
WIRE 16 -1 (-2075 3725)(-2075 3575);
WIRE 16 -1 (-1875 3725)(-1875 3575);
WIRE 16 -1 (-1875 3575)(-1625 3575);
WIRE 16 -1 (-1300 3575)(-1625 3575);
WIRE 16 -1 (-1625 3725)(-1625 3575);
WIRE 16 -1 (-1300 3725)(-1300 3575);
WIRE 16 -1 (-1025 3575)(-1300 3575);
WIRE 16 -1 (-650 3575)(-1025 3575);
WIRE 16 -1 (-1025 3700)(-1025 3575);
WIRE 16 -1 (-650 3575)(-650 3700);
WIRE 16 -1 (-650 3500)(-650 3575);
WIRE 16 -1 (-2500 4075)(-2075 4075);
WIRE 16 -1 (-2500 3925)(-2500 4075);
WIRE 16 -1 (-2500 4075)(-3225 4075);
WIRE 16 -1 (-2075 4075)(-1875 4075);
WIRE 16 -1 (-2075 3925)(-2075 4075);
WIRE 16 -1 (-1875 4075)(-1625 4075);
WIRE 16 -1 (-1875 3925)(-1875 4075);
WIRE 16 -1 (-1625 4075)(-1300 4075);
WIRE 16 -1 (-1625 4075)(-1625 3925);
WIRE 16 -1 (-1025 4075)(-1300 4075);
WIRE 16 -1 (-1300 4075)(-1300 3925);
WIRE 16 -1 (-650 4075)(-1025 4075);
WIRE 16 -1 (-1025 3900)(-1025 4075);
WIRE 16 -1 (0 4075)(-650 4075);
WIRE 16 -1 (-650 4075)(-650 4000);
WIRE 16 -1 (-650 4000)(-200 4000);
WIRE 16 -1 (-650 4000)(-650 3900);
WIRE 16 -1 (0 4075)(0 4550);
WIRE 16 -1 (0 4075)(0 3925);
WIRE 16 -1 (-200 4000)(-200 3300);
WIRE 16 -1 (-200 3300)(-1400 3300);
WIRE 17 273 (-2625 3075)(-200 3075);
WIRE 17 273 (-2625 3075)(-2625 2200);
WIRE 17 273 (-200 3075)(-200 2200);
WIRE 17 273 (-2625 2200)(-200 2200);
WIRE 16 -1 (-2100 2825)(-825 2825);
FORCEPROP 2 LAST SIG_NAME VSENSE_PVDD18_S5_P1_DP
J 0
(-1610 2835);
DISPLAY 0.489362 (-1610 2835);
WIRE 16 -1 (-2100 2575)(-825 2575);
FORCEPROP 2 LAST SIG_NAME VSENSE_PVDD18_S5_P1_DN
J 0
(-1610 2585);
DISPLAY 0.489362 (-1610 2585);
WIRE 17 273 (-1725 2950)(-525 2950);
WIRE 17 273 (-1725 2950)(-1725 2450);
WIRE 17 273 (-525 2950)(-525 2450);
WIRE 17 273 (-1725 2450)(-525 2450);
WIRE 16 -1 (-3525 4575)(-2825 4575);
FORCEPROP 2 LAST SIG_NAME PWRGD_PVDD18_S5_R_P1
J 0
(-3360 4585);
DISPLAY 0.489362 (-3360 4585);
WIRE 17 273 (-1250 7125)(325 7125);
WIRE 17 273 (-1250 7125)(-1250 6175);
WIRE 17 273 (325 7125)(325 6175);
WIRE 17 273 (-1250 6175)(325 6175);
DOT 1 (-7775 4075);
DOT 1 (-2800 3625);
DOT 1 (-1875 3575);
DOT 1 (-650 4075);
DOT 1 (-650 4000);
DOT 1 (-4425 4575);
DOT 1 (-6925 3275);
DOT 1 (-4925 3225);
DOT 1 (-4750 3375);
DOT 1 (-4200 4075);
DOT 1 (-7800 4403);
DOT 1 (-8075 4850);
DOT 1 (-7625 4403);
DOT 1 (-7225 4403);
DOT 1 (-7625 4850);
DOT 1 (-7225 4850);
DOT 1 (-6775 4403);
DOT 1 (-6775 4850);
DOT 1 (-6375 4850);
DOT 1 (-6050 4575);
DOT 1 (-3925 3025);
DOT 1 (-3350 2575);
DOT 1 (-3700 3625);
DOT 1 (-3925 3625);
DOT 1 (-2975 3625);
DOT 1 (-2075 3575);
DOT 1 (-2500 4075);
DOT 1 (-2075 4075);
DOT 1 (-1625 3575);
DOT 1 (-1875 4075);
DOT 1 (-1625 4075);
DOT 1 (-1300 3575);
DOT 1 (-1025 3575);
DOT 1 (-1300 4075);
DOT 1 (-1025 4075);
DOT 1 (-650 3575);
DOT 1 (0 4075);
DOT 1 (-4050 3375);
FORCENOTE
2ND SOURCE:PC22 CHANGE TO CH5104KEB02
(-8675 1750) 0;
DISPLAY LEFT (-8675 1750);
DISPLAY 1.021277 (-8675 1750);
PAINT WHITE (-8675 1750);
FORCENOTE
PC64 CHANGE TO CH13306JB14
(-8150 1650) 0;
DISPLAY LEFT (-8150 1650);
DISPLAY 1.021277 (-8150 1650);
PAINT WHITE (-8150 1650);
FORCENOTE
MAIN SOURCE:
(-8675 1850) 0;
DISPLAY LEFT (-8675 1850);
DISPLAY 1.021277 (-8675 1850);
PAINT WHITE (-8675 1850);
FORCENOTE
BOM CHANGE
(-8675 2000) 0;
DISPLAY LEFT (-8675 2000);
DISPLAY 1.276596 (-8675 2000);
PAINT WHITE (-8675 2000);
FORCENOTE
2ND SOURCE:AL000548007/TPS548B28RWWR
(-8675 2300) 0;
DISPLAY LEFT (-8675 2300);
DISPLAY 1.021277 (-8675 2300);
PAINT WHITE (-8675 2300);
FORCENOTE
MAIN SOURCE:AL008633005/MPQ8633BGLE-C807-Z
(-8675 2400) 0;
DISPLAY LEFT (-8675 2400);
DISPLAY 1.021277 (-8675 2400);
PAINT WHITE (-8675 2400);
FORCENOTE
PCMC063T-1R0MN
(-3125 4325) 0;
DISPLAY LEFT (-3125 4325);
DISPLAY 0.638298 (-3125 4325);
PAINT WHITE (-3125 4325);
FORCENOTE
RA
(-3350 3750) 0;
DISPLAY LEFT (-3350 3750);
DISPLAY 1.021277 (-3350 3750);
PAINT WHITE (-3350 3750);
FORCENOTE
VOUT=0.6(1+RA/RB)=1.8V
(-4775 1975) 0;
DISPLAY LEFT (-4775 1975);
DISPLAY 2.000000 (-4775 1975);
PAINT WHITE (-4775 1975);
FORCENOTE
BOM NOTE
(-8675 2550) 0;
DISPLAY LEFT (-8675 2550);
DISPLAY 1.276596 (-8675 2550);
PAINT WHITE (-8675 2550);
FORCENOTE
FSW=600KHZ
(-8175 3500) 0;
DISPLAY LEFT (-8175 3500);
DISPLAY 1.276596 (-8175 3500);
PAINT WHITE (-8175 3500);
FORCENOTE
FCCM
(-8175 3600) 0;
DISPLAY LEFT (-8175 3600);
DISPLAY 1.276596 (-8175 3600);
PAINT WHITE (-8175 3600);
FORCENOTE
RIPPLE=+/-20MV
(-1225 6850) 0;
DISPLAY LEFT (-1225 6850);
DISPLAY 0.936170 (-1225 6850);
PAINT WHITE (-1225 6850);
FORCENOTE
RB
(-4025 3400) 0;
DISPLAY LEFT (-4025 3400);
DISPLAY 1.021277 (-4025 3400);
PAINT WHITE (-4025 3400);
FORCENOTE
TRACE SPACING = 5MIL
(-1375 2225) 0;
DISPLAY LEFT (-1375 2225);
DISPLAY 1.021277 (-1375 2225);
PAINT WHITE (-1375 2225);
FORCENOTE
DIFFERENTIAL PAIR
(-1375 2375) 0;
DISPLAY LEFT (-1375 2375);
DISPLAY 1.021277 (-1375 2375);
PAINT WHITE (-1375 2375);
FORCENOTE
IRATED=5A@125C
(-8700 4775) 0;
DISPLAY LEFT (-8700 4775);
DISPLAY 0.808511 (-8700 4775);
PAINT WHITE (-8700 4775);
FORCENOTE
PVDD18_S5_P1
(-5750 6100) 0;
DISPLAY LEFT (-5750 6100);
DISPLAY 3.148936 (-5750 6100);
PAINT WHITE (-5750 6100);
FORCENOTE
NEAR CPU SIDE
(-2600 2225) 0;
DISPLAY LEFT (-2600 2225);
DISPLAY 1.021277 (-2600 2225);
PAINT GREEN (-2600 2225);
FORCENOTE
TRACE WIDTH = 10MIL
(-1375 2300) 0;
DISPLAY LEFT (-1375 2300);
DISPLAY 1.021277 (-1375 2300);
PAINT WHITE (-1375 2300);
FORCENOTE
5.0*5.8
(-1100 3475) 0;
DISPLAY LEFT (-1100 3475);
DISPLAY 0.638298 (-1100 3475);
PAINT WHITE (-1100 3475);
FORCENOTE
ESR= 10 MOHM
(-1125 3525) 0;
DISPLAY LEFT (-1125 3525);
DISPLAY 0.638298 (-1125 3525);
PAINT WHITE (-1125 3525);
FORCENOTE
OUTPUT VOLTAGE=1.8V+/-40MV
(-1225 6925) 0;
DISPLAY LEFT (-1225 6925);
DISPLAY 0.936170 (-1225 6925);
PAINT WHITE (-1225 6925);
FORCENOTE
AC TOLERANCE=+/-30MV
(-1225 6775) 0;
DISPLAY LEFT (-1225 6775);
DISPLAY 0.936170 (-1225 6775);
PAINT WHITE (-1225 6775);
FORCENOTE
TDC=10A
(-1225 6700) 0;
DISPLAY LEFT (-1225 6700);
DISPLAY 0.936170 (-1225 6700);
PAINT WHITE (-1225 6700);
FORCENOTE
LOAD RELEASE=1.5A
(-1225 6400) 0;
DISPLAY LEFT (-1225 6400);
DISPLAY 0.936170 (-1225 6400);
PAINT WHITE (-1225 6400);
FORCENOTE
EFFICIENCY > 90% @TDC
(-1225 6250) 0;
DISPLAY LEFT (-1225 6250);
DISPLAY 0.936170 (-1225 6250);
PAINT WHITE (-1225 6250);
FORCENOTE
WORK FREQUENCY=600KHZ
(-1225 6325) 0;
DISPLAY LEFT (-1225 6325);
DISPLAY 0.936170 (-1225 6325);
PAINT WHITE (-1225 6325);
FORCENOTE
LOAD STEP=1.5A
(-1225 6475) 0;
DISPLAY LEFT (-1225 6475);
DISPLAY 0.936170 (-1225 6475);
PAINT WHITE (-1225 6475);
FORCENOTE
OCP=15A (EDC*1.2)
(-1225 6550) 0;
DISPLAY LEFT (-1225 6550);
DISPLAY 0.936170 (-1225 6550);
PAINT WHITE (-1225 6550);
FORCENOTE
EDC=12A
(-1225 6625) 0;
DISPLAY LEFT (-1225 6625);
DISPLAY 0.936170 (-1225 6625);
PAINT WHITE (-1225 6625);
FORCENOTE
PVDD18_S5_P1 SPECFICATION
(-1225 7050) 0;
DISPLAY LEFT (-1225 7050);
DISPLAY 1.276596 (-1225 7050);
PAINT WHITE (-1225 7050);
FORCENOTE
DCR=10M OHM
(-3125 4175) 0;
DISPLAY LEFT (-3125 4175);
DISPLAY 0.638298 (-3125 4175);
PAINT WHITE (-3125 4175);
FORCENOTE
ISAT:20A@100C
(-3125 4275) 0;
DISPLAY LEFT (-3125 4275);
DISPLAY 0.638298 (-3125 4275);
PAINT WHITE (-3125 4275);
FORCENOTE
6.6*6.6*3.0
(-3125 4225) 0;
DISPLAY LEFT (-3125 4225);
DISPLAY 0.638298 (-3125 4225);
PAINT WHITE (-3125 4225);
FORCENOTE
2ND=CV-10M0MZ02
(-3125 4125) 0;
DISPLAY LEFT (-3125 4125);
DISPLAY 0.638298 (-3125 4125);
PAINT WHITE (-3125 4125);
FORCENOTE
DCR=5M OHM
(-8700 4725) 0;
DISPLAY LEFT (-8700 4725);
DISPLAY 0.808511 (-8700 4725);
PAINT WHITE (-8700 4725);
FORCENOTE
2ND=CX220Z06Z00
(-8700 4675) 0;
DISPLAY LEFT (-8700 4675);
DISPLAY 0.808511 (-8700 4675);
PAINT WHITE (-8700 4675);
FORCENOTE
3RD=CX000220000
(-8700 4625) 0;
DISPLAY LEFT (-8700 4625);
DISPLAY 0.808511 (-8700 4625);
PAINT WHITE (-8700 4625);
QUIT
